FILE_TYPE = MACRO_DRAWING;
SET COLOR_WIRE YELLOW;
SET COLOR_PROP ORANGE;
SET COLOR_DOT WHITE;
SET COLOR_ARC YELLOW;
SET COLOR_BODY GREEN;
SET COLOR_NOTE PURPLE;
SET PROP_DISPLAY VALUE;
SET PAGE_NUMBER P198;
FORCEADD UNIVERSAL_GND..1
(-11925 1725);
FORCEPROP 3 LASTPIN (-11925 1775) SIG_NAME GND\g
J 0
(-11915 1785);
DISPLAY 0.659574 (-11915 1785);
PAINT MONO (-11915 1785);
DISPLAY INVISIBLE (-11915 1785);
FORCEPROP 2 LAST CDS_LIB pure_quanta_power
J 0
(-11925 1725);
DISPLAY INVISIBLE (-11925 1725);
FORCEPROP 1 LAST HDL_POWER GND
J 1
(-11900 1650);
DISPLAY 0.872340 (-11900 1650);
PAINT GREEN (-11900 1650);
DISPLAY INVISIBLE (-11900 1650);
FORCEPROP 1 LAST PATH I1
J 0
(-11850 1725);
DISPLAY 0.872340 (-11850 1725);
PAINT AQUA (-11850 1725);
DISPLAY INVISIBLE (-11850 1725);
FORCEADD Q_CAP..1
(-11050 2700);
FORCEPROP 1 LAST LOCATION PC616
J 0
(-11000 2800);
DISPLAY 0.489362 (-11000 2800);
PAINT SKYBLUE (-11000 2800);
FORCEPROP 0 LAST $SEC 1
J 0
(-11000 2850);
DISPLAY 0.680851 (-11000 2850);
PAINT MONO (-11000 2850);
DISPLAY INVISIBLE (-11000 2850);
FORCEPROP 0 LAST CDS_SEC 1
J 0
(-11000 2850);
DISPLAY 1.021277 (-11000 2850);
DISPLAY INVISIBLE (-11000 2850);
FORCEPROP 1 LASTPIN (-11050 2800) $PN 1
J 0
(-11040 2780);
DISPLAY 0.489362 (-11040 2780);
PAINT MONO (-11040 2780);
FORCEPROP 1 LASTPIN (-11050 2600) $PN 2
J 0
(-11040 2580);
DISPLAY 0.489362 (-11040 2580);
PAINT MONO (-11040 2580);
FORCEPROP 1 LAST PACK_TYPE C0402
J 0
(-11000 2500);
DISPLAY 0.489362 (-11000 2500);
PAINT SKYBLUE (-11000 2500);
FORCEPROP 1 LAST VOLTAGE 10V
J 0
(-11000 2700);
DISPLAY 0.489362 (-11000 2700);
PAINT SKYBLUE (-11000 2700);
FORCEPROP 1 LAST VALUE 2.2UF
J 0
(-11000 2750);
DISPLAY 0.489362 (-11000 2750);
PAINT SKYBLUE (-11000 2750);
FORCEPROP 1 LAST TOLERANCE 10%
J 0
(-11000 2650);
DISPLAY 0.489362 (-11000 2650);
PAINT SKYBLUE (-11000 2650);
FORCEPROP 1 LAST MATERIAL X6S
J 0
(-11000 2600);
DISPLAY 0.489362 (-11000 2600);
PAINT SKYBLUE (-11000 2600);
FORCEPROP 2 LAST CDS_LIB pure_quanta
J 0
(-11050 2700);
DISPLAY INVISIBLE (-11050 2700);
FORCEPROP 1 LAST PATH I10
J 0
(-11000 2850);
DISPLAY 0.978723 (-11000 2850);
PAINT WHITE (-11000 2850);
DISPLAY INVISIBLE (-11000 2850);
FORCEPROP 1 LAST PART_NUMBER CH5222KEB01
J 0
(-11000 2550);
DISPLAY 0.489362 (-11000 2550);
PAINT SKYBLUE (-11000 2550);
DISPLAY INVISIBLE (-11000 2550);
FORCEADD UNIVERSAL_GND..1
(-10700 3000);
FORCEPROP 3 LASTPIN (-10700 3050) SIG_NAME GND\g
J 0
(-10690 3060);
DISPLAY 0.659574 (-10690 3060);
PAINT MONO (-10690 3060);
DISPLAY INVISIBLE (-10690 3060);
FORCEPROP 2 LAST CDS_LIB pure_quanta_power
J 0
(-10700 3000);
DISPLAY INVISIBLE (-10700 3000);
FORCEPROP 1 LAST HDL_POWER GND
J 1
(-10675 2925);
DISPLAY 0.872340 (-10675 2925);
PAINT GREEN (-10675 2925);
DISPLAY INVISIBLE (-10675 2925);
FORCEPROP 1 LAST PATH I11
J 0
(-10625 3000);
DISPLAY 0.872340 (-10625 3000);
PAINT AQUA (-10625 3000);
DISPLAY INVISIBLE (-10625 3000);
FORCEADD Q_RES..2
(-11050 3250);
FORCEPROP 1 LAST LOCATION PR370
J 0
(-11005 3375);
DISPLAY 0.489362 (-11005 3375);
PAINT SKYBLUE (-11005 3375);
FORCEPROP 0 LAST $SEC 1
J 0
(-11000 3425);
DISPLAY 0.680851 (-11000 3425);
PAINT MONO (-11000 3425);
DISPLAY INVISIBLE (-11000 3425);
FORCEPROP 0 LAST CDS_SEC 1
J 0
(-11000 3425);
DISPLAY 1.021277 (-11000 3425);
DISPLAY INVISIBLE (-11000 3425);
FORCEPROP 1 LASTPIN (-11050 3350) $PN 1
J 0
(-11045 3312);
DISPLAY 0.489362 (-11045 3312);
PAINT MONO (-11045 3312);
FORCEPROP 1 LASTPIN (-11050 3150) $PN 2
J 0
(-11045 3160);
DISPLAY 0.489362 (-11045 3160);
PAINT MONO (-11045 3160);
FORCEPROP 1 LAST WATTAGE 1/16W
J 0
(-11000 3225);
DISPLAY 0.489362 (-11000 3225);
PAINT SKYBLUE (-11000 3225);
FORCEPROP 1 LAST MATERIAL CHIP
J 0
(-11000 3175);
DISPLAY 0.489362 (-11000 3175);
PAINT SKYBLUE (-11000 3175);
FORCEPROP 1 LAST TOLERANCE 1%
J 0
(-11000 3275);
DISPLAY 0.489362 (-11000 3275);
PAINT SKYBLUE (-11000 3275);
FORCEPROP 1 LAST VALUE 2.2
J 0
(-11000 3325);
DISPLAY 0.489362 (-11000 3325);
PAINT SKYBLUE (-11000 3325);
FORCEPROP 1 LAST PACK_TYPE 0402LF
J 0
(-11000 3075);
DISPLAY 0.489362 (-11000 3075);
PAINT SKYBLUE (-11000 3075);
FORCEPROP 2 LAST CDS_LIB pure_quanta
J 0
(-11050 3250);
DISPLAY INVISIBLE (-11050 3250);
FORCEPROP 1 LAST PATH I12
J 0
(-11000 3425);
DISPLAY 0.978723 (-11000 3425);
PAINT WHITE (-11000 3425);
DISPLAY INVISIBLE (-11000 3425);
FORCEPROP 1 LAST PART_NUMBER CS-2202FB01
J 0
(-11000 3125);
DISPLAY 0.489362 (-11000 3125);
PAINT SKYBLUE (-11000 3125);
DISPLAY INVISIBLE (-11000 3125);
FORCEADD Q_CAP..1
(-10700 3275);
FORCEPROP 1 LAST LOCATION PC618_IOP1_4
J 0
(-10650 3375);
DISPLAY 0.489362 (-10650 3375);
PAINT SKYBLUE (-10650 3375);
FORCEPROP 0 LAST $SEC 1
J 0
(-10650 3425);
DISPLAY 0.680851 (-10650 3425);
PAINT MONO (-10650 3425);
DISPLAY INVISIBLE (-10650 3425);
FORCEPROP 0 LAST CDS_SEC 1
J 0
(-10650 3425);
DISPLAY 1.021277 (-10650 3425);
DISPLAY INVISIBLE (-10650 3425);
FORCEPROP 1 LASTPIN (-10700 3375) $PN 1
J 0
(-10690 3355);
DISPLAY 0.489362 (-10690 3355);
PAINT MONO (-10690 3355);
FORCEPROP 1 LASTPIN (-10700 3175) $PN 2
J 0
(-10690 3155);
DISPLAY 0.489362 (-10690 3155);
PAINT MONO (-10690 3155);
FORCEPROP 1 LAST PACK_TYPE C0402
J 0
(-10650 3075);
DISPLAY 0.489362 (-10650 3075);
PAINT SKYBLUE (-10650 3075);
FORCEPROP 1 LAST VOLTAGE 10V
J 0
(-10650 3275);
DISPLAY 0.489362 (-10650 3275);
PAINT SKYBLUE (-10650 3275);
FORCEPROP 1 LAST VALUE 2.2UF
J 0
(-10650 3325);
DISPLAY 0.489362 (-10650 3325);
PAINT SKYBLUE (-10650 3325);
FORCEPROP 1 LAST TOLERANCE 10%
J 0
(-10650 3225);
DISPLAY 0.489362 (-10650 3225);
PAINT SKYBLUE (-10650 3225);
FORCEPROP 1 LAST MATERIAL X6S
J 0
(-10650 3175);
DISPLAY 0.489362 (-10650 3175);
PAINT SKYBLUE (-10650 3175);
FORCEPROP 2 LAST CDS_LIB pure_quanta
J 0
(-10700 3275);
DISPLAY INVISIBLE (-10700 3275);
FORCEPROP 1 LAST PATH I13
J 0
(-10650 3425);
DISPLAY 0.978723 (-10650 3425);
PAINT WHITE (-10650 3425);
DISPLAY INVISIBLE (-10650 3425);
FORCEPROP 1 LAST PART_NUMBER CH5222KEB01
J 0
(-10650 3125);
DISPLAY 0.489362 (-10650 3125);
PAINT SKYBLUE (-10650 3125);
DISPLAY INVISIBLE (-10650 3125);
FORCEADD VCC_CORE..1
(-11050 3650);
FORCEPROP 3 LASTPIN (-11050 3600) SIG_NAME PVDDCR_CPU1_P1_PVCC\g
J 0
(-11040 3610);
DISPLAY 0.659574 (-11040 3610);
PAINT MONO (-11040 3610);
DISPLAY INVISIBLE (-11040 3610);
FORCEPROP 1 LAST HDL_POWER PVDDCR_CPU1_P1_PVCC
J 1
(-11050 3700);
DISPLAY 0.489362 (-11050 3700);
PAINT GREEN (-11050 3700);
FORCEPROP 2 LAST CDS_LIB pure_quanta_power
J 0
(-11050 3650);
DISPLAY INVISIBLE (-11050 3650);
FORCEPROP 1 LAST PATH I14
J 0
(-11000 3675);
DISPLAY 0.872340 (-11000 3675);
PAINT AQUA (-11000 3675);
DISPLAY INVISIBLE (-11000 3675);
FORCEADD ISL99390FRZTR5935..1
(-9350 2300);
FORCEPROP 1 LAST LOCATION PU53
J 0
(-9650 3175);
DISPLAY 0.489362 (-9650 3175);
PAINT SKYBLUE (-9650 3175);
FORCEPROP 2 LAST $SEC 1
J 0
(-9650 3225);
DISPLAY 0.680851 (-9650 3225);
PAINT MONO (-9650 3225);
DISPLAY INVISIBLE (-9650 3225);
FORCEPROP 2 LAST CDS_SEC 1
J 0
(-9600 3300);
DISPLAY 1.021277 (-9600 3300);
DISPLAY INVISIBLE (-9600 3300);
FORCEPROP 2 LASTPIN (-8950 1850) $PN 2
J 0
(-8940 1860);
DISPLAY 0.489362 (-8940 1860);
PAINT MONO (-8940 1860);
FORCEPROP 2 LASTPIN (-8950 2650) $PN 33
J 0
(-8940 2660);
DISPLAY 0.489362 (-8940 2660);
PAINT MONO (-8940 2660);
FORCEPROP 2 LASTPIN (-9800 2050) $PN 31
J 2
(-9810 2060);
DISPLAY 0.489362 (-9810 2060);
PAINT MONO (-9810 2060);
FORCEPROP 2 LASTPIN (-9800 2450) $PN 35
J 2
(-9810 2460);
DISPLAY 0.489362 (-9810 2460);
PAINT MONO (-9810 2460);
FORCEPROP 2 LASTPIN (-8950 2000) $PN 6
J 0
(-8940 2010);
DISPLAY 0.489362 (-8940 2010);
PAINT MONO (-8940 2010);
FORCEPROP 2 LASTPIN (-8950 1950) $PN 41
J 0
(-8940 1960);
DISPLAY 0.489362 (-8940 1960);
PAINT MONO (-8940 1960);
FORCEPROP 2 LASTPIN (-9800 2300) $PN 38
J 2
(-9810 2310);
DISPLAY 0.489362 (-9810 2310);
PAINT MONO (-9810 2310);
FORCEPROP 2 LASTPIN (-9800 2000) $PN 37
J 2
(-9810 2010);
DISPLAY 0.489362 (-9810 2010);
PAINT MONO (-9810 2010);
FORCEPROP 2 LASTPIN (-8950 1800) $PN 5
J 0
(-8940 1810);
DISPLAY 0.489362 (-8940 1810);
PAINT MONO (-8940 1810);
FORCEPROP 2 LASTPIN (-8950 1750) $PN 7_9-20_24
J 0
(-8940 1760);
DISPLAY 0.489362 (-8940 1760);
PAINT MONO (-8940 1760);
FORCEPROP 2 LASTPIN (-8950 1700) $PN 40
J 0
(-8940 1710);
DISPLAY 0.489362 (-8940 1710);
PAINT MONO (-8940 1710);
FORCEPROP 2 LASTPIN (-8950 2400) $PN 32
J 0
(-8940 2410);
DISPLAY 0.489362 (-8940 2410);
PAINT MONO (-8940 2410);
FORCEPROP 2 LASTPIN (-9800 2950) $PN 4
J 2
(-9810 2960);
DISPLAY 0.489362 (-9810 2960);
PAINT MONO (-9810 2960);
FORCEPROP 2 LASTPIN (-9800 1700) $PN 34
J 2
(-9810 1710);
DISPLAY 0.489362 (-9810 1710);
PAINT MONO (-9810 1710);
FORCEPROP 2 LASTPIN (-9800 2200) $PN 39
J 2
(-9810 2210);
DISPLAY 0.489362 (-9810 2210);
PAINT MONO (-9810 2210);
FORCEPROP 2 LASTPIN (-8950 2300) $PN 10_19
J 0
(-8940 2310);
DISPLAY 0.489362 (-8940 2310);
PAINT MONO (-8940 2310);
FORCEPROP 2 LASTPIN (-9800 1800) $PN 36
J 2
(-9810 1810);
DISPLAY 0.489362 (-9810 1810);
PAINT MONO (-9810 1810);
FORCEPROP 2 LASTPIN (-9800 2650) $PN 3
J 2
(-9810 2660);
DISPLAY 0.489362 (-9810 2660);
PAINT MONO (-9810 2660);
FORCEPROP 2 LASTPIN (-8950 2950) $PN 25_29
J 0
(-8940 2960);
DISPLAY 0.489362 (-8940 2960);
PAINT MONO (-8940 2960);
FORCEPROP 2 LASTPIN (-8950 2900) $PN 30
J 0
(-8940 2910);
DISPLAY 0.489362 (-8940 2910);
PAINT MONO (-8940 2910);
FORCEPROP 2 LASTPIN (-8950 2050) $PN 1
J 0
(-8940 2060);
DISPLAY 0.489362 (-8940 2060);
PAINT MONO (-8940 2060);
FORCEPROP 2 LAST VALUE ISL99390FRZ-TR5935
J 0
(-9650 3250);
DISPLAY 0.489362 (-9650 3250);
PAINT SKYBLUE (-9650 3250);
FORCEPROP 1 LAST MATERIAL IC
J 0
(-9650 3025);
DISPLAY 0.489362 (-9650 3025);
PAINT SKYBLUE (-9650 3025);
FORCEPROP 2 LAST PART_TYPE SMLF
J 0
(-9650 3300);
DISPLAY 0.638298 (-9650 3300);
FORCEPROP 1 LAST NEEDS_NO_SIZE TRUE
J 0
(-9350 2300);
DISPLAY 0.723404 (-9350 2300);
PAINT GREEN (-9350 2300);
DISPLAY INVISIBLE (-9350 2300);
FORCEPROP 1 LAST CDS_LMAN_SYM_OUTLINE -300,700,250,-650
J 0
(-9350 2300);
DISPLAY 0.468085 (-9350 2300);
PAINT GREEN (-9350 2300);
DISPLAY INVISIBLE (-9350 2300);
FORCEPROP 2 LAST CDS_LIB pure_quanta
J 0
(-9350 2300);
DISPLAY INVISIBLE (-9350 2300);
FORCEPROP 1 LAST PATH I15
J 0
(-9350 2300);
DISPLAY 0.723404 (-9350 2300);
PAINT GREEN (-9350 2300);
DISPLAY INVISIBLE (-9350 2300);
FORCEPROP 1 LAST PART_NUMBER AL099390004
J 0
(-9650 3100);
DISPLAY 0.489362 (-9650 3100);
PAINT SKYBLUE (-9650 3100);
DISPLAY INVISIBLE (-9650 3100);
FORCEADD UNIVERSAL_GND..1
(-8700 1575);
FORCEPROP 3 LASTPIN (-8700 1625) SIG_NAME GND\g
J 0
(-8690 1635);
DISPLAY 0.659574 (-8690 1635);
PAINT MONO (-8690 1635);
DISPLAY INVISIBLE (-8690 1635);
FORCEPROP 2 LAST CDS_LIB pure_quanta_power
J 0
(-8700 1575);
PAINT MONO (-8700 1575);
DISPLAY INVISIBLE (-8700 1575);
FORCEPROP 1 LAST HDL_POWER GND
J 1
(-8675 1500);
DISPLAY 0.872340 (-8675 1500);
PAINT GREEN (-8675 1500);
DISPLAY INVISIBLE (-8675 1500);
FORCEPROP 1 LAST PATH I16
J 0
(-8625 1575);
DISPLAY 0.872340 (-8625 1575);
PAINT AQUA (-8625 1575);
DISPLAY INVISIBLE (-8625 1575);
FORCEADD Q_RES..1
(-8050 2650);
FORCEPROP 1 LAST LOCATION PR372
J 0
(-8075 2700);
DISPLAY 0.489362 (-8075 2700);
PAINT SKYBLUE (-8075 2700);
FORCEPROP 0 LAST $SEC 1
J 0
(-7775 2750);
DISPLAY 0.680851 (-7775 2750);
PAINT MONO (-7775 2750);
DISPLAY INVISIBLE (-7775 2750);
FORCEPROP 0 LAST CDS_SEC 1
J 0
(-7775 2750);
DISPLAY 1.021277 (-7775 2750);
DISPLAY INVISIBLE (-7775 2750);
FORCEPROP 1 LASTPIN (-8150 2650) $PN 1
J 0
(-8138 2662);
DISPLAY 0.787234 (-8138 2662);
PAINT MONO (-8138 2662);
DISPLAY INVISIBLE (-8138 2662);
FORCEPROP 1 LASTPIN (-7950 2650) $PN 2
J 0
(-7988 2662);
DISPLAY 0.787234 (-7988 2662);
PAINT MONO (-7988 2662);
DISPLAY INVISIBLE (-7988 2662);
FORCEPROP 1 LAST MATERIAL CHIP
J 0
(-7950 2600);
DISPLAY 0.489362 (-7950 2600);
PAINT SKYBLUE (-7950 2600);
FORCEPROP 1 LAST TOLERANCE 1%
J 0
(-8225 2550);
DISPLAY 0.489362 (-8225 2550);
PAINT SKYBLUE (-8225 2550);
FORCEPROP 1 LAST PACK_TYPE 0402LF
J 0
(-7975 2550);
DISPLAY 0.489362 (-7975 2550);
PAINT SKYBLUE (-7975 2550);
FORCEPROP 1 LAST WATTAGE 1/16W
J 2
(-7825 2675);
DISPLAY 0.489362 (-7825 2675);
PAINT SKYBLUE (-7825 2675);
FORCEPROP 1 LAST VALUE 5.6
J 2
(-8150 2675);
DISPLAY 0.489362 (-8150 2675);
PAINT SKYBLUE (-8150 2675);
FORCEPROP 2 LAST CDS_LIB pure_quanta
J 0
(-8050 2650);
DISPLAY INVISIBLE (-8050 2650);
FORCEPROP 1 LAST PATH I17
J 0
(-8100 2800);
DISPLAY 0.978723 (-8100 2800);
PAINT WHITE (-8100 2800);
DISPLAY INVISIBLE (-8100 2800);
FORCEPROP 1 LAST PART_NUMBER CS-5602FB01
J 0
(-8350 2600);
DISPLAY 0.489362 (-8350 2600);
PAINT SKYBLUE (-8350 2600);
DISPLAY INVISIBLE (-8350 2600);
FORCEADD Q_CAP..1
(-8475 3275);
FORCEPROP 1 LAST LOCATION PC623_4
J 0
(-8425 3375);
DISPLAY 0.489362 (-8425 3375);
PAINT SKYBLUE (-8425 3375);
FORCEPROP 0 LAST $SEC 1
J 0
(-8425 3425);
DISPLAY 0.680851 (-8425 3425);
PAINT MONO (-8425 3425);
DISPLAY INVISIBLE (-8425 3425);
FORCEPROP 0 LAST CDS_SEC 1
J 0
(-8425 3425);
DISPLAY 1.021277 (-8425 3425);
DISPLAY INVISIBLE (-8425 3425);
FORCEPROP 1 LASTPIN (-8475 3375) $PN 1
J 0
(-8465 3355);
DISPLAY 0.489362 (-8465 3355);
PAINT MONO (-8465 3355);
FORCEPROP 1 LASTPIN (-8475 3175) $PN 2
J 0
(-8465 3155);
DISPLAY 0.489362 (-8465 3155);
PAINT MONO (-8465 3155);
FORCEPROP 1 LAST PACK_TYPE 0402
J 0
(-8425 3075);
DISPLAY 0.489362 (-8425 3075);
PAINT SKYBLUE (-8425 3075);
FORCEPROP 1 LAST VOLTAGE 25V
J 0
(-8425 3275);
DISPLAY 0.489362 (-8425 3275);
PAINT SKYBLUE (-8425 3275);
FORCEPROP 1 LAST VALUE 0.1UF
J 0
(-8425 3325);
DISPLAY 0.489362 (-8425 3325);
PAINT SKYBLUE (-8425 3325);
FORCEPROP 1 LAST TOLERANCE 10%
J 0
(-8425 3225);
DISPLAY 0.489362 (-8425 3225);
PAINT SKYBLUE (-8425 3225);
FORCEPROP 1 LAST MATERIAL X7R
J 0
(-8425 3175);
DISPLAY 0.489362 (-8425 3175);
PAINT SKYBLUE (-8425 3175);
FORCEPROP 2 LAST CDS_LIB pure_quanta
J 0
(-8475 3275);
DISPLAY INVISIBLE (-8475 3275);
FORCEPROP 1 LAST PATH I18
J 0
(-8425 3425);
DISPLAY 0.978723 (-8425 3425);
PAINT WHITE (-8425 3425);
DISPLAY INVISIBLE (-8425 3425);
FORCEPROP 1 LAST PART_NUMBER CH4104K1B00
J 0
(-8425 3125);
DISPLAY 0.489362 (-8425 3125);
PAINT SKYBLUE (-8425 3125);
DISPLAY INVISIBLE (-8425 3125);
FORCEADD UNIVERSAL_GND..1
(-11900 4525);
FORCEPROP 3 LASTPIN (-11900 4575) SIG_NAME GND\g
J 0
(-11890 4585);
DISPLAY 0.659574 (-11890 4585);
PAINT MONO (-11890 4585);
DISPLAY INVISIBLE (-11890 4585);
FORCEPROP 2 LAST CDS_LIB pure_quanta_power
J 0
(-11900 4525);
DISPLAY INVISIBLE (-11900 4525);
FORCEPROP 1 LAST HDL_POWER GND
J 1
(-11875 4450);
DISPLAY 0.872340 (-11875 4450);
PAINT GREEN (-11875 4450);
DISPLAY INVISIBLE (-11875 4450);
FORCEPROP 1 LAST PATH I19
J 0
(-11825 4525);
DISPLAY 0.872340 (-11825 4525);
PAINT AQUA (-11825 4525);
DISPLAY INVISIBLE (-11825 4525);
FORCEADD Q_CAP..1
(-11925 1925);
FORCEPROP 1 LAST LOCATION PC621_10
J 0
(-11875 2025);
DISPLAY 0.489362 (-11875 2025);
PAINT SKYBLUE (-11875 2025);
FORCEPROP 0 LAST $SEC 1
J 0
(-11875 2050);
DISPLAY 0.680851 (-11875 2050);
PAINT MONO (-11875 2050);
DISPLAY INVISIBLE (-11875 2050);
FORCEPROP 2 LAST CDS_SEC 1
J 0
(-11925 2175);
DISPLAY 1.021277 (-11925 2175);
DISPLAY INVISIBLE (-11925 2175);
FORCEPROP 1 LASTPIN (-11925 2025) $PN 1
J 0
(-11915 2005);
DISPLAY 0.489362 (-11915 2005);
PAINT MONO (-11915 2005);
FORCEPROP 1 LASTPIN (-11925 1825) $PN 2
J 0
(-11915 1805);
DISPLAY 0.489362 (-11915 1805);
PAINT MONO (-11915 1805);
FORCEPROP 1 LAST PACK_TYPE 0402
J 0
(-11875 1725);
DISPLAY 0.489362 (-11875 1725);
PAINT SKYBLUE (-11875 1725);
FORCEPROP 1 LAST VOLTAGE 25V
J 0
(-11875 1925);
DISPLAY 0.489362 (-11875 1925);
PAINT SKYBLUE (-11875 1925);
FORCEPROP 1 LAST VALUE 0.1UF
J 0
(-11875 1975);
DISPLAY 0.489362 (-11875 1975);
PAINT SKYBLUE (-11875 1975);
FORCEPROP 1 LAST TOLERANCE 10%
J 0
(-11875 1875);
DISPLAY 0.489362 (-11875 1875);
PAINT SKYBLUE (-11875 1875);
FORCEPROP 1 LAST MATERIAL X7R
J 0
(-11875 1825);
DISPLAY 0.489362 (-11875 1825);
PAINT SKYBLUE (-11875 1825);
FORCEPROP 2 LAST CDS_LIB pure_quanta
J 0
(-11925 1925);
PAINT MONO (-11925 1925);
DISPLAY INVISIBLE (-11925 1925);
FORCEPROP 1 LAST PATH I2
J 0
(-11875 2075);
DISPLAY 0.978723 (-11875 2075);
PAINT WHITE (-11875 2075);
DISPLAY INVISIBLE (-11875 2075);
FORCEPROP 1 LAST PART_NUMBER CH4104K1B00
J 0
(-11875 1775);
DISPLAY 0.489362 (-11875 1775);
PAINT SKYBLUE (-11875 1775);
DISPLAY INVISIBLE (-11875 1775);
FORCEADD Q_CAP..1
(-11900 4725);
FORCEPROP 1 LAST LOCATION PC620_9
J 0
(-11850 4825);
DISPLAY 0.489362 (-11850 4825);
PAINT SKYBLUE (-11850 4825);
FORCEPROP 0 LAST $SEC 1
J 0
(-11850 4850);
DISPLAY 0.680851 (-11850 4850);
PAINT MONO (-11850 4850);
DISPLAY INVISIBLE (-11850 4850);
FORCEPROP 0 LAST CDS_SEC 1
J 0
(-11650 4775);
DISPLAY 1.021277 (-11650 4775);
DISPLAY INVISIBLE (-11650 4775);
FORCEPROP 1 LASTPIN (-11900 4825) $PN 1
J 0
(-11890 4805);
DISPLAY 0.489362 (-11890 4805);
PAINT MONO (-11890 4805);
FORCEPROP 1 LASTPIN (-11900 4625) $PN 2
J 0
(-11890 4605);
DISPLAY 0.489362 (-11890 4605);
PAINT MONO (-11890 4605);
FORCEPROP 1 LAST PACK_TYPE 0402
J 0
(-11850 4525);
DISPLAY 0.489362 (-11850 4525);
PAINT SKYBLUE (-11850 4525);
FORCEPROP 1 LAST VOLTAGE 25V
J 0
(-11850 4725);
DISPLAY 0.489362 (-11850 4725);
PAINT SKYBLUE (-11850 4725);
FORCEPROP 1 LAST VALUE 0.1UF
J 0
(-11850 4775);
DISPLAY 0.489362 (-11850 4775);
PAINT SKYBLUE (-11850 4775);
FORCEPROP 1 LAST TOLERANCE 10%
J 0
(-11850 4675);
DISPLAY 0.489362 (-11850 4675);
PAINT SKYBLUE (-11850 4675);
FORCEPROP 1 LAST MATERIAL X7R
J 0
(-11850 4625);
DISPLAY 0.489362 (-11850 4625);
PAINT SKYBLUE (-11850 4625);
FORCEPROP 2 LAST CDS_LIB pure_quanta
J 0
(-11900 4725);
DISPLAY INVISIBLE (-11900 4725);
FORCEPROP 1 LAST PATH I20
J 0
(-11850 4875);
DISPLAY 0.978723 (-11850 4875);
PAINT WHITE (-11850 4875);
DISPLAY INVISIBLE (-11850 4875);
FORCEPROP 1 LAST PART_NUMBER CH4104K1B00
J 0
(-11850 4575);
DISPLAY 0.489362 (-11850 4575);
PAINT SKYBLUE (-11850 4575);
DISPLAY INVISIBLE (-11850 4575);
FORCEADD UNIVERSAL_GND..1
(-11350 4425);
FORCEPROP 3 LASTPIN (-11350 4475) SIG_NAME GND\g
J 0
(-11340 4485);
DISPLAY 0.659574 (-11340 4485);
PAINT MONO (-11340 4485);
DISPLAY INVISIBLE (-11340 4485);
FORCEPROP 2 LAST CDS_LIB pure_quanta_power
J 0
(-11350 4425);
PAINT MONO (-11350 4425);
DISPLAY INVISIBLE (-11350 4425);
FORCEPROP 1 LAST HDL_POWER GND
J 1
(-11325 4350);
DISPLAY 0.872340 (-11325 4350);
PAINT GREEN (-11325 4350);
DISPLAY INVISIBLE (-11325 4350);
FORCEPROP 1 LAST PATH I21
J 0
(-11275 4425);
DISPLAY 0.872340 (-11275 4425);
PAINT AQUA (-11275 4425);
DISPLAY INVISIBLE (-11275 4425);
FORCEADD Q_RES..2
R 2
(-11350 4650);
FORCEPROP 1 LAST LOCATION PR369
J 2
(-11395 4775);
DISPLAY 0.489362 (-11395 4775);
PAINT SKYBLUE (-11395 4775);
FORCEPROP 0 LAST $SEC 1
J 2
(-11400 4825);
DISPLAY 0.680851 (-11400 4825);
PAINT MONO (-11400 4825);
DISPLAY INVISIBLE (-11400 4825);
FORCEPROP 0 LAST CDS_SEC 1
J 2
(-11400 4825);
DISPLAY 1.021277 (-11400 4825);
DISPLAY INVISIBLE (-11400 4825);
FORCEPROP 1 LASTPIN (-11350 4750) $PN 1
J 2
(-11355 4712);
DISPLAY 0.489362 (-11355 4712);
PAINT MONO (-11355 4712);
FORCEPROP 1 LASTPIN (-11350 4550) $PN 2
J 2
(-11355 4560);
DISPLAY 0.489362 (-11355 4560);
PAINT MONO (-11355 4560);
FORCEPROP 1 LAST PACK_TYPE 0402LF
J 2
(-11400 4475);
DISPLAY 0.489362 (-11400 4475);
PAINT SKYBLUE (-11400 4475);
FORCEPROP 1 LAST VALUE 8.87K
J 2
(-11405 4725);
DISPLAY 0.489362 (-11405 4725);
PAINT SKYBLUE (-11405 4725);
FORCEPROP 1 LAST TOLERANCE 1%
J 2
(-11405 4675);
DISPLAY 0.489362 (-11405 4675);
PAINT SKYBLUE (-11405 4675);
FORCEPROP 1 LAST MATERIAL EMPTY
J 2
(-11400 4575);
DISPLAY 0.489362 (-11400 4575);
PAINT RED (-11400 4575);
FORCEPROP 1 LAST WATTAGE 1/16W
J 2
(-11400 4625);
DISPLAY 0.489362 (-11400 4625);
PAINT SKYBLUE (-11400 4625);
FORCEPROP 2 LAST CDS_LIB pure_quanta
J 2
(-11350 4650);
DISPLAY INVISIBLE (-11350 4650);
FORCEPROP 1 LAST PATH I22
J 2
(-11400 4825);
DISPLAY 0.978723 (-11400 4825);
PAINT WHITE (-11400 4825);
DISPLAY INVISIBLE (-11400 4825);
FORCEPROP 1 LAST PART_NUMBER CS28872FB01
J 2
(-11400 4525);
DISPLAY 0.489362 (-11400 4525);
PAINT SKYBLUE (-11400 4525);
DISPLAY INVISIBLE (-11400 4525);
FORCEADD OFFPAGE..1
(-10875 4500);
FORCEPROP 2 LAST $XR0 217 
J 0
(-11127 4500);
DISPLAY 0.638298 (-11127 4500);
PAINT MONO (-11127 4500);
FORCEPROP 2 LAST CDS_LIB standard
J 0
(-10875 4500);
DISPLAY INVISIBLE (-10875 4500);
FORCEPROP 1 LAST OFFPAGE TRUE
J 0
(-10550 4375);
DISPLAY 0.872340 (-10550 4375);
PAINT GREEN (-10550 4375);
DISPLAY INVISIBLE (-10550 4375);
FORCEPROP 1 LAST COMMENT_BODY TRUE
J 0
(-10750 4400);
DISPLAY 0.872340 (-10750 4400);
PAINT GREEN (-10750 4400);
DISPLAY INVISIBLE (-10750 4400);
FORCEPROP 2 LAST PATH I23
J 0
(-11150 4550);
DISPLAY 0.680851 (-11150 4550);
DISPLAY INVISIBLE (-11150 4550);
FORCEADD OFFPAGE..5
(-10875 4600);
FORCEPROP 2 LAST $XR2 217 
J 0
(-11130 4636);
DISPLAY 0.638298 (-11130 4636);
PAINT MONO (-11130 4636);
FORCEPROP 2 LAST $XR1 223 
J 0
(-11130 4564);
DISPLAY 0.638298 (-11130 4564);
PAINT MONO (-11130 4564);
FORCEPROP 2 LAST $XR0 222 
J 0
(-11130 4600);
DISPLAY 0.638298 (-11130 4600);
PAINT MONO (-11130 4600);
FORCEPROP 2 LAST CDS_LIB standard
J 0
(-10875 4600);
DISPLAY INVISIBLE (-10875 4600);
FORCEPROP 1 LAST OFFPAGE TRUE
J 0
(-10550 4475);
DISPLAY 0.872340 (-10550 4475);
PAINT GREEN (-10550 4475);
DISPLAY INVISIBLE (-10550 4475);
FORCEPROP 1 LAST COMMENT_BODY TRUE
J 0
(-10775 4525);
DISPLAY 0.872340 (-10775 4525);
PAINT GREEN (-10775 4525);
DISPLAY INVISIBLE (-10775 4525);
FORCEPROP 2 LAST PATH I24
J 0
(-11125 4675);
DISPLAY 0.680851 (-11125 4675);
DISPLAY INVISIBLE (-11125 4675);
FORCEADD OFFPAGE..1
(-10875 5000);
FORCEPROP 2 LAST $XR5 223 
J 0
(-11727 5000);
DISPLAY 0.638298 (-11727 5000);
PAINT MONO (-11727 5000);
FORCEPROP 2 LAST $XR4 222 
J 0
(-11607 5000);
DISPLAY 0.638298 (-11607 5000);
PAINT MONO (-11607 5000);
FORCEPROP 2 LAST $XR3 220 
J 0
(-11487 5000);
DISPLAY 0.638298 (-11487 5000);
PAINT MONO (-11487 5000);
FORCEPROP 2 LAST $XR2 219 
J 0
(-11367 5000);
DISPLAY 0.638298 (-11367 5000);
PAINT MONO (-11367 5000);
FORCEPROP 2 LAST $XR1 218 
J 0
(-11247 5000);
DISPLAY 0.638298 (-11247 5000);
PAINT MONO (-11247 5000);
FORCEPROP 2 LAST $XR0 217 
J 0
(-11127 5000);
DISPLAY 0.638298 (-11127 5000);
PAINT MONO (-11127 5000);
FORCEPROP 2 LAST CDS_LIB standard
J 0
(-10875 5000);
DISPLAY INVISIBLE (-10875 5000);
FORCEPROP 1 LAST OFFPAGE TRUE
J 0
(-10550 4875);
DISPLAY 0.872340 (-10550 4875);
PAINT GREEN (-10550 4875);
DISPLAY INVISIBLE (-10550 4875);
FORCEPROP 1 LAST COMMENT_BODY TRUE
J 0
(-10750 4900);
DISPLAY 0.872340 (-10750 4900);
PAINT GREEN (-10750 4900);
DISPLAY INVISIBLE (-10750 4900);
FORCEPROP 2 LAST PATH I25
J 0
(-11150 5050);
DISPLAY 0.680851 (-11150 5050);
DISPLAY INVISIBLE (-11150 5050);
FORCEADD OFFPAGE..5
(-10875 5100);
FORCEPROP 2 LAST $XR0 217 
J 0
(-11130 5100);
DISPLAY 0.638298 (-11130 5100);
PAINT MONO (-11130 5100);
FORCEPROP 2 LAST CDS_LIB standard
J 0
(-10875 5100);
DISPLAY INVISIBLE (-10875 5100);
FORCEPROP 1 LAST OFFPAGE TRUE
J 0
(-10550 4975);
DISPLAY 0.872340 (-10550 4975);
PAINT GREEN (-10550 4975);
DISPLAY INVISIBLE (-10550 4975);
FORCEPROP 1 LAST COMMENT_BODY TRUE
J 0
(-10775 5025);
DISPLAY 0.872340 (-10775 5025);
PAINT GREEN (-10775 5025);
DISPLAY INVISIBLE (-10775 5025);
FORCEPROP 2 LAST PATH I26
J 0
(-11125 5150);
DISPLAY 0.680851 (-11125 5150);
DISPLAY INVISIBLE (-11125 5150);
FORCEADD UNIVERSAL_GND..1
(-11025 5200);
FORCEPROP 3 LASTPIN (-11025 5250) SIG_NAME GND\g
J 0
(-11015 5260);
DISPLAY 0.659574 (-11015 5260);
PAINT MONO (-11015 5260);
DISPLAY INVISIBLE (-11015 5260);
FORCEPROP 2 LAST CDS_LIB pure_quanta_power
J 0
(-11025 5200);
DISPLAY INVISIBLE (-11025 5200);
FORCEPROP 1 LAST HDL_POWER GND
J 1
(-11000 5125);
DISPLAY 0.872340 (-11000 5125);
PAINT GREEN (-11000 5125);
DISPLAY INVISIBLE (-11000 5125);
FORCEPROP 1 LAST PATH I27
J 0
(-10950 5200);
DISPLAY 0.872340 (-10950 5200);
PAINT AQUA (-10950 5200);
DISPLAY INVISIBLE (-10950 5200);
FORCEADD Q_CAP..1
(-11025 5400);
FORCEPROP 1 LAST LOCATION PC617
J 0
(-10975 5500);
DISPLAY 0.489362 (-10975 5500);
PAINT SKYBLUE (-10975 5500);
FORCEPROP 0 LAST $SEC 1
J 0
(-10975 5550);
DISPLAY 0.680851 (-10975 5550);
PAINT MONO (-10975 5550);
DISPLAY INVISIBLE (-10975 5550);
FORCEPROP 0 LAST CDS_SEC 1
J 0
(-10975 5550);
DISPLAY 1.021277 (-10975 5550);
DISPLAY INVISIBLE (-10975 5550);
FORCEPROP 1 LASTPIN (-11025 5500) $PN 1
J 0
(-11015 5480);
DISPLAY 0.489362 (-11015 5480);
PAINT MONO (-11015 5480);
FORCEPROP 1 LASTPIN (-11025 5300) $PN 2
J 0
(-11015 5280);
DISPLAY 0.489362 (-11015 5280);
PAINT MONO (-11015 5280);
FORCEPROP 1 LAST PACK_TYPE C0402
J 0
(-10975 5200);
DISPLAY 0.489362 (-10975 5200);
PAINT SKYBLUE (-10975 5200);
FORCEPROP 1 LAST VOLTAGE 10V
J 0
(-10975 5400);
DISPLAY 0.489362 (-10975 5400);
PAINT SKYBLUE (-10975 5400);
FORCEPROP 1 LAST VALUE 2.2UF
J 0
(-10975 5450);
DISPLAY 0.489362 (-10975 5450);
PAINT SKYBLUE (-10975 5450);
FORCEPROP 1 LAST TOLERANCE 10%
J 0
(-10975 5350);
DISPLAY 0.489362 (-10975 5350);
PAINT SKYBLUE (-10975 5350);
FORCEPROP 1 LAST MATERIAL X6S
J 0
(-10975 5300);
DISPLAY 0.489362 (-10975 5300);
PAINT SKYBLUE (-10975 5300);
FORCEPROP 2 LAST CDS_LIB pure_quanta
J 0
(-11025 5400);
DISPLAY INVISIBLE (-11025 5400);
FORCEPROP 1 LAST PATH I28
J 0
(-10975 5550);
DISPLAY 0.978723 (-10975 5550);
PAINT WHITE (-10975 5550);
DISPLAY INVISIBLE (-10975 5550);
FORCEPROP 1 LAST PART_NUMBER CH5222KEB01
J 0
(-10975 5250);
DISPLAY 0.489362 (-10975 5250);
PAINT SKYBLUE (-10975 5250);
DISPLAY INVISIBLE (-10975 5250);
FORCEADD Q_RES..2
(-11025 5950);
FORCEPROP 1 LAST LOCATION PR371
J 0
(-10980 6075);
DISPLAY 0.489362 (-10980 6075);
PAINT SKYBLUE (-10980 6075);
FORCEPROP 0 LAST $SEC 1
J 0
(-10975 6125);
DISPLAY 0.680851 (-10975 6125);
PAINT MONO (-10975 6125);
DISPLAY INVISIBLE (-10975 6125);
FORCEPROP 0 LAST CDS_SEC 1
J 0
(-10975 6125);
DISPLAY 1.021277 (-10975 6125);
DISPLAY INVISIBLE (-10975 6125);
FORCEPROP 1 LASTPIN (-11025 6050) $PN 1
J 0
(-11020 6012);
DISPLAY 0.489362 (-11020 6012);
PAINT MONO (-11020 6012);
FORCEPROP 1 LASTPIN (-11025 5850) $PN 2
J 0
(-11020 5860);
DISPLAY 0.489362 (-11020 5860);
PAINT MONO (-11020 5860);
FORCEPROP 1 LAST WATTAGE 1/16W
J 0
(-10975 5925);
DISPLAY 0.489362 (-10975 5925);
PAINT SKYBLUE (-10975 5925);
FORCEPROP 1 LAST MATERIAL CHIP
J 0
(-10975 5875);
DISPLAY 0.489362 (-10975 5875);
PAINT SKYBLUE (-10975 5875);
FORCEPROP 1 LAST TOLERANCE 1%
J 0
(-10975 5975);
DISPLAY 0.489362 (-10975 5975);
PAINT SKYBLUE (-10975 5975);
FORCEPROP 1 LAST VALUE 2.2
J 0
(-10975 6025);
DISPLAY 0.489362 (-10975 6025);
PAINT SKYBLUE (-10975 6025);
FORCEPROP 1 LAST PACK_TYPE 0402LF
J 0
(-10975 5775);
DISPLAY 0.489362 (-10975 5775);
PAINT SKYBLUE (-10975 5775);
FORCEPROP 2 LAST CDS_LIB pure_quanta
J 0
(-11025 5950);
DISPLAY INVISIBLE (-11025 5950);
FORCEPROP 1 LAST PATH I29
J 0
(-10975 6125);
DISPLAY 0.978723 (-10975 6125);
PAINT WHITE (-10975 6125);
DISPLAY INVISIBLE (-10975 6125);
FORCEPROP 1 LAST PART_NUMBER CS-2202FB01
J 0
(-10975 5825);
DISPLAY 0.489362 (-10975 5825);
PAINT SKYBLUE (-10975 5825);
DISPLAY INVISIBLE (-10975 5825);
FORCEADD UNIVERSAL_GND..1
(-11375 1575);
FORCEPROP 3 LASTPIN (-11375 1625) SIG_NAME GND\g
J 0
(-11365 1635);
DISPLAY 0.659574 (-11365 1635);
PAINT MONO (-11365 1635);
DISPLAY INVISIBLE (-11365 1635);
FORCEPROP 2 LAST CDS_LIB pure_quanta_power
J 0
(-11375 1575);
PAINT MONO (-11375 1575);
DISPLAY INVISIBLE (-11375 1575);
FORCEPROP 1 LAST HDL_POWER GND
J 1
(-11350 1500);
DISPLAY 0.872340 (-11350 1500);
PAINT GREEN (-11350 1500);
DISPLAY INVISIBLE (-11350 1500);
FORCEPROP 1 LAST PATH I3
J 0
(-11300 1575);
DISPLAY 0.872340 (-11300 1575);
PAINT AQUA (-11300 1575);
DISPLAY INVISIBLE (-11300 1575);
FORCEADD UNIVERSAL_GND..1
(-10675 5700);
FORCEPROP 3 LASTPIN (-10675 5750) SIG_NAME GND\g
J 0
(-10665 5760);
DISPLAY 0.659574 (-10665 5760);
PAINT MONO (-10665 5760);
DISPLAY INVISIBLE (-10665 5760);
FORCEPROP 2 LAST CDS_LIB pure_quanta_power
J 0
(-10675 5700);
DISPLAY INVISIBLE (-10675 5700);
FORCEPROP 1 LAST HDL_POWER GND
J 1
(-10650 5625);
DISPLAY 0.872340 (-10650 5625);
PAINT GREEN (-10650 5625);
DISPLAY INVISIBLE (-10650 5625);
FORCEPROP 1 LAST PATH I30
J 0
(-10600 5700);
DISPLAY 0.872340 (-10600 5700);
PAINT AQUA (-10600 5700);
DISPLAY INVISIBLE (-10600 5700);
FORCEADD Q_CAP..1
(-10675 5975);
FORCEPROP 1 LAST LOCATION PC619_IOP1_3
J 0
(-10625 6075);
DISPLAY 0.489362 (-10625 6075);
PAINT SKYBLUE (-10625 6075);
FORCEPROP 0 LAST $SEC 1
J 0
(-10625 6125);
DISPLAY 0.680851 (-10625 6125);
PAINT MONO (-10625 6125);
DISPLAY INVISIBLE (-10625 6125);
FORCEPROP 0 LAST CDS_SEC 1
J 0
(-10625 6125);
DISPLAY 1.021277 (-10625 6125);
DISPLAY INVISIBLE (-10625 6125);
FORCEPROP 1 LASTPIN (-10675 6075) $PN 1
J 0
(-10665 6055);
DISPLAY 0.489362 (-10665 6055);
PAINT MONO (-10665 6055);
FORCEPROP 1 LASTPIN (-10675 5875) $PN 2
J 0
(-10665 5855);
DISPLAY 0.489362 (-10665 5855);
PAINT MONO (-10665 5855);
FORCEPROP 1 LAST PACK_TYPE C0402
J 0
(-10625 5775);
DISPLAY 0.489362 (-10625 5775);
PAINT SKYBLUE (-10625 5775);
FORCEPROP 1 LAST VOLTAGE 10V
J 0
(-10625 5975);
DISPLAY 0.489362 (-10625 5975);
PAINT SKYBLUE (-10625 5975);
FORCEPROP 1 LAST VALUE 2.2UF
J 0
(-10625 6025);
DISPLAY 0.489362 (-10625 6025);
PAINT SKYBLUE (-10625 6025);
FORCEPROP 1 LAST TOLERANCE 10%
J 0
(-10625 5925);
DISPLAY 0.489362 (-10625 5925);
PAINT SKYBLUE (-10625 5925);
FORCEPROP 1 LAST MATERIAL X6S
J 0
(-10625 5875);
DISPLAY 0.489362 (-10625 5875);
PAINT SKYBLUE (-10625 5875);
FORCEPROP 2 LAST CDS_LIB pure_quanta
J 0
(-10675 5975);
DISPLAY INVISIBLE (-10675 5975);
FORCEPROP 1 LAST PATH I31
J 0
(-10625 6125);
DISPLAY 0.978723 (-10625 6125);
PAINT WHITE (-10625 6125);
DISPLAY INVISIBLE (-10625 6125);
FORCEPROP 1 LAST PART_NUMBER CH5222KEB01
J 0
(-10625 5825);
DISPLAY 0.489362 (-10625 5825);
PAINT SKYBLUE (-10625 5825);
DISPLAY INVISIBLE (-10625 5825);
FORCEADD VCC_CORE..1
(-11025 6350);
FORCEPROP 3 LASTPIN (-11025 6300) SIG_NAME PVDDCR_CPU1_P1_PVCC\g
J 0
(-11015 6310);
DISPLAY 0.659574 (-11015 6310);
PAINT MONO (-11015 6310);
DISPLAY INVISIBLE (-11015 6310);
FORCEPROP 1 LAST HDL_POWER PVDDCR_CPU1_P1_PVCC
J 1
(-11025 6400);
DISPLAY 0.489362 (-11025 6400);
PAINT GREEN (-11025 6400);
FORCEPROP 2 LAST CDS_LIB pure_quanta_power
J 0
(-11025 6350);
DISPLAY INVISIBLE (-11025 6350);
FORCEPROP 1 LAST PATH I32
J 0
(-10975 6375);
DISPLAY 0.872340 (-10975 6375);
PAINT AQUA (-10975 6375);
DISPLAY INVISIBLE (-10975 6375);
FORCEADD UNIVERSAL_GND..1
(-8700 4375);
FORCEPROP 3 LASTPIN (-8700 4425) SIG_NAME GND\g
J 0
(-8690 4435);
DISPLAY 0.659574 (-8690 4435);
PAINT MONO (-8690 4435);
DISPLAY INVISIBLE (-8690 4435);
FORCEPROP 2 LAST CDS_LIB pure_quanta_power
J 0
(-8700 4375);
PAINT MONO (-8700 4375);
DISPLAY INVISIBLE (-8700 4375);
FORCEPROP 1 LAST HDL_POWER GND
J 1
(-8675 4300);
DISPLAY 0.872340 (-8675 4300);
PAINT GREEN (-8675 4300);
DISPLAY INVISIBLE (-8675 4300);
FORCEPROP 1 LAST PATH I33
J 0
(-8625 4375);
DISPLAY 0.872340 (-8625 4375);
PAINT AQUA (-8625 4375);
DISPLAY INVISIBLE (-8625 4375);
FORCEADD Q_RES..1
(-7975 5450);
FORCEPROP 1 LAST LOCATION PR373
J 0
(-8025 5500);
DISPLAY 0.489362 (-8025 5500);
PAINT SKYBLUE (-8025 5500);
FORCEPROP 0 LAST $SEC 1
J 0
(-7700 5550);
DISPLAY 0.680851 (-7700 5550);
PAINT MONO (-7700 5550);
DISPLAY INVISIBLE (-7700 5550);
FORCEPROP 0 LAST CDS_SEC 1
J 0
(-7700 5550);
DISPLAY 1.021277 (-7700 5550);
DISPLAY INVISIBLE (-7700 5550);
FORCEPROP 1 LASTPIN (-8075 5450) $PN 1
J 0
(-8063 5462);
DISPLAY 0.787234 (-8063 5462);
PAINT MONO (-8063 5462);
DISPLAY INVISIBLE (-8063 5462);
FORCEPROP 1 LASTPIN (-7875 5450) $PN 2
J 0
(-7913 5462);
DISPLAY 0.787234 (-7913 5462);
PAINT MONO (-7913 5462);
DISPLAY INVISIBLE (-7913 5462);
FORCEPROP 1 LAST WATTAGE 1/16W
J 2
(-7775 5475);
DISPLAY 0.489362 (-7775 5475);
PAINT SKYBLUE (-7775 5475);
FORCEPROP 1 LAST MATERIAL CHIP
J 0
(-7875 5400);
DISPLAY 0.489362 (-7875 5400);
PAINT SKYBLUE (-7875 5400);
FORCEPROP 1 LAST PACK_TYPE 0402LF
J 0
(-7875 5350);
DISPLAY 0.489362 (-7875 5350);
PAINT SKYBLUE (-7875 5350);
FORCEPROP 1 LAST VALUE 5.6
J 2
(-8100 5475);
DISPLAY 0.489362 (-8100 5475);
PAINT SKYBLUE (-8100 5475);
FORCEPROP 1 LAST TOLERANCE 1%
J 0
(-8150 5350);
DISPLAY 0.489362 (-8150 5350);
PAINT SKYBLUE (-8150 5350);
FORCEPROP 2 LAST CDS_LIB pure_quanta
J 0
(-7975 5450);
DISPLAY INVISIBLE (-7975 5450);
FORCEPROP 1 LAST PATH I34
J 0
(-8025 5600);
DISPLAY 0.978723 (-8025 5600);
PAINT WHITE (-8025 5600);
DISPLAY INVISIBLE (-8025 5600);
FORCEPROP 1 LAST PART_NUMBER CS-5602FB01
J 0
(-8275 5400);
DISPLAY 0.489362 (-8275 5400);
PAINT SKYBLUE (-8275 5400);
DISPLAY INVISIBLE (-8275 5400);
FORCEADD Q_CAP..1
(-8500 6050);
FORCEPROP 1 LAST LOCATION PC622_3
J 0
(-8450 6150);
DISPLAY 0.489362 (-8450 6150);
PAINT SKYBLUE (-8450 6150);
FORCEPROP 0 LAST $SEC 1
J 0
(-8450 6200);
DISPLAY 0.680851 (-8450 6200);
PAINT MONO (-8450 6200);
DISPLAY INVISIBLE (-8450 6200);
FORCEPROP 0 LAST CDS_SEC 1
J 0
(-8450 6200);
DISPLAY 1.021277 (-8450 6200);
DISPLAY INVISIBLE (-8450 6200);
FORCEPROP 1 LASTPIN (-8500 6150) $PN 1
J 0
(-8490 6130);
DISPLAY 0.489362 (-8490 6130);
PAINT MONO (-8490 6130);
FORCEPROP 1 LASTPIN (-8500 5950) $PN 2
J 0
(-8490 5930);
DISPLAY 0.489362 (-8490 5930);
PAINT MONO (-8490 5930);
FORCEPROP 1 LAST VOLTAGE 25V
J 0
(-8450 6050);
DISPLAY 0.489362 (-8450 6050);
PAINT SKYBLUE (-8450 6050);
FORCEPROP 1 LAST VALUE 0.1UF
J 0
(-8450 6100);
DISPLAY 0.489362 (-8450 6100);
PAINT SKYBLUE (-8450 6100);
FORCEPROP 1 LAST TOLERANCE 10%
J 0
(-8450 6000);
DISPLAY 0.489362 (-8450 6000);
PAINT SKYBLUE (-8450 6000);
FORCEPROP 1 LAST MATERIAL X7R
J 0
(-8450 5950);
DISPLAY 0.489362 (-8450 5950);
PAINT SKYBLUE (-8450 5950);
FORCEPROP 1 LAST PACK_TYPE 0402
J 0
(-8450 5850);
DISPLAY 0.489362 (-8450 5850);
PAINT SKYBLUE (-8450 5850);
FORCEPROP 2 LAST CDS_LIB pure_quanta
J 0
(-8500 6050);
DISPLAY INVISIBLE (-8500 6050);
FORCEPROP 1 LAST PATH I35
J 0
(-8450 6200);
DISPLAY 0.978723 (-8450 6200);
PAINT WHITE (-8450 6200);
DISPLAY INVISIBLE (-8450 6200);
FORCEPROP 1 LAST PART_NUMBER CH4104K1B00
J 0
(-8450 5900);
DISPLAY 0.489362 (-8450 5900);
PAINT SKYBLUE (-8450 5900);
DISPLAY INVISIBLE (-8450 5900);
FORCEADD Q_CAP..1
(-8075 6050);
FORCEPROP 1 LAST LOCATION PC624_3
J 0
(-8025 6200);
DISPLAY 0.489362 (-8025 6200);
PAINT SKYBLUE (-8025 6200);
FORCEPROP 0 LAST $SEC 1
J 0
(-8025 6250);
DISPLAY 0.680851 (-8025 6250);
PAINT MONO (-8025 6250);
DISPLAY INVISIBLE (-8025 6250);
FORCEPROP 0 LAST CDS_SEC 1
J 0
(-8025 6250);
DISPLAY 1.021277 (-8025 6250);
DISPLAY INVISIBLE (-8025 6250);
FORCEPROP 1 LASTPIN (-8075 6150) $PN 1
J 0
(-8065 6130);
DISPLAY 0.489362 (-8065 6130);
PAINT MONO (-8065 6130);
FORCEPROP 1 LASTPIN (-8075 5950) $PN 2
J 0
(-8065 5930);
DISPLAY 0.489362 (-8065 5930);
PAINT MONO (-8065 5930);
FORCEPROP 1 LAST PACK_TYPE C0402
J 0
(-8025 5950);
DISPLAY 0.489362 (-8025 5950);
PAINT SKYBLUE (-8025 5950);
FORCEPROP 1 LAST VOLTAGE 25V
J 0
(-8025 6100);
DISPLAY 0.489362 (-8025 6100);
PAINT SKYBLUE (-8025 6100);
FORCEPROP 1 LAST VALUE 1UF
J 0
(-8025 6150);
DISPLAY 0.489362 (-8025 6150);
PAINT SKYBLUE (-8025 6150);
FORCEPROP 1 LAST TOLERANCE 10%
J 0
(-8025 6050);
DISPLAY 0.489362 (-8025 6050);
PAINT SKYBLUE (-8025 6050);
FORCEPROP 1 LAST MATERIAL X6S
J 0
(-8025 6000);
DISPLAY 0.489362 (-8025 6000);
PAINT SKYBLUE (-8025 6000);
FORCEPROP 2 LAST CDS_LIB pure_quanta
J 0
(-8075 6050);
DISPLAY INVISIBLE (-8075 6050);
FORCEPROP 1 LAST PATH I36
J 0
(-8025 6200);
DISPLAY 0.978723 (-8025 6200);
PAINT WHITE (-8025 6200);
DISPLAY INVISIBLE (-8025 6200);
FORCEPROP 1 LAST PART_NUMBER CH5104KEB02
J 0
(-8025 5900);
DISPLAY 0.489362 (-8025 5900);
PAINT SKYBLUE (-8025 5900);
DISPLAY INVISIBLE (-8025 5900);
FORCEADD Q_CAP..1
(-8025 2100);
FORCEPROP 1 LAST LOCATION PC176
J 0
(-7975 2200);
DISPLAY 0.489362 (-7975 2200);
PAINT SKYBLUE (-7975 2200);
FORCEPROP 0 LAST $SEC 1
J 0
(-7975 2250);
DISPLAY 0.680851 (-7975 2250);
PAINT MONO (-7975 2250);
DISPLAY INVISIBLE (-7975 2250);
FORCEPROP 0 LAST CDS_SEC 1
J 0
(-7975 2250);
DISPLAY 1.021277 (-7975 2250);
DISPLAY INVISIBLE (-7975 2250);
FORCEPROP 1 LASTPIN (-8025 2200) $PN 1
J 0
(-8015 2180);
DISPLAY 0.489362 (-8015 2180);
PAINT MONO (-8015 2180);
FORCEPROP 1 LASTPIN (-8025 2000) $PN 2
J 0
(-8015 1980);
DISPLAY 0.489362 (-8015 1980);
PAINT MONO (-8015 1980);
FORCEPROP 1 LAST MATERIAL EMPTY
J 0
(-7975 2000);
DISPLAY 0.489362 (-7975 2000);
PAINT RED (-7975 2000);
FORCEPROP 1 LAST VOLTAGE 50V
J 0
(-7975 2100);
DISPLAY 0.489362 (-7975 2100);
PAINT SKYBLUE (-7975 2100);
FORCEPROP 1 LAST PACK_TYPE C0402
J 0
(-7975 1900);
DISPLAY 0.489362 (-7975 1900);
PAINT SKYBLUE (-7975 1900);
FORCEPROP 1 LAST VALUE 560PF
J 0
(-7975 2150);
DISPLAY 0.489362 (-7975 2150);
PAINT SKYBLUE (-7975 2150);
FORCEPROP 1 LAST TOLERANCE 10%
J 0
(-7975 2050);
DISPLAY 0.489362 (-7975 2050);
PAINT SKYBLUE (-7975 2050);
FORCEPROP 2 LAST CDS_LIB pure_quanta
J 0
(-8025 2100);
DISPLAY INVISIBLE (-8025 2100);
FORCEPROP 1 LAST PATH I37
J 0
(-7975 2250);
DISPLAY 0.978723 (-7975 2250);
PAINT WHITE (-7975 2250);
DISPLAY INVISIBLE (-7975 2250);
FORCEPROP 1 LAST PART_NUMBER CH1566K1B09
J 0
(-7975 1950);
DISPLAY 0.489362 (-7975 1950);
PAINT SKYBLUE (-7975 1950);
DISPLAY INVISIBLE (-7975 1950);
FORCEADD UNIVERSAL_GND..1
(-8025 1375);
FORCEPROP 3 LASTPIN (-8025 1425) SIG_NAME GND\g
J 0
(-8015 1435);
DISPLAY 0.659574 (-8015 1435);
PAINT MONO (-8015 1435);
DISPLAY INVISIBLE (-8015 1435);
FORCEPROP 2 LAST CDS_LIB pure_quanta_power
J 0
(-8025 1375);
DISPLAY INVISIBLE (-8025 1375);
FORCEPROP 1 LAST HDL_POWER GND
J 1
(-8000 1300);
DISPLAY 0.872340 (-8000 1300);
PAINT GREEN (-8000 1300);
DISPLAY INVISIBLE (-8000 1300);
FORCEPROP 1 LAST PATH I38
J 0
(-7950 1375);
DISPLAY 0.872340 (-7950 1375);
PAINT AQUA (-7950 1375);
DISPLAY INVISIBLE (-7950 1375);
FORCEADD Q_RES..2
(-8025 1600);
FORCEPROP 1 LAST LOCATION PR491
J 0
(-7980 1725);
DISPLAY 0.489362 (-7980 1725);
PAINT SKYBLUE (-7980 1725);
FORCEPROP 0 LAST $SEC 1
J 0
(-7975 1775);
DISPLAY 0.680851 (-7975 1775);
PAINT MONO (-7975 1775);
DISPLAY INVISIBLE (-7975 1775);
FORCEPROP 0 LAST CDS_SEC 1
J 0
(-7975 1775);
DISPLAY 1.021277 (-7975 1775);
DISPLAY INVISIBLE (-7975 1775);
FORCEPROP 1 LASTPIN (-8025 1700) $PN 1
J 0
(-8020 1662);
DISPLAY 0.489362 (-8020 1662);
PAINT MONO (-8020 1662);
FORCEPROP 1 LASTPIN (-8025 1500) $PN 2
J 0
(-8020 1510);
DISPLAY 0.489362 (-8020 1510);
PAINT MONO (-8020 1510);
FORCEPROP 1 LAST PACK_TYPE 0402LF
J 0
(-7985 1425);
DISPLAY 0.489362 (-7985 1425);
PAINT SKYBLUE (-7985 1425);
FORCEPROP 1 LAST VALUE 1.5
J 0
(-7980 1675);
DISPLAY 0.489362 (-7980 1675);
PAINT SKYBLUE (-7980 1675);
FORCEPROP 1 LAST TOLERANCE 1%
J 0
(-7980 1625);
DISPLAY 0.489362 (-7980 1625);
PAINT SKYBLUE (-7980 1625);
FORCEPROP 1 LAST MATERIAL EMPTY
J 0
(-7985 1525);
DISPLAY 0.489362 (-7985 1525);
PAINT RED (-7985 1525);
FORCEPROP 1 LAST WATTAGE 1/8W
J 0
(-7985 1575);
DISPLAY 0.489362 (-7985 1575);
PAINT SKYBLUE (-7985 1575);
FORCEPROP 2 LAST CDS_LIB pure_quanta
J 0
(-8025 1600);
DISPLAY INVISIBLE (-8025 1600);
FORCEPROP 1 LAST PATH I39
J 0
(-7975 1775);
DISPLAY 0.978723 (-7975 1775);
PAINT WHITE (-7975 1775);
DISPLAY INVISIBLE (-7975 1775);
FORCEPROP 1 LAST PART_NUMBER CS-1504FB00
J 0
(-7985 1475);
DISPLAY 0.489362 (-7985 1475);
PAINT SKYBLUE (-7985 1475);
DISPLAY INVISIBLE (-7985 1475);
FORCEADD Q_RES..2
R 2
(-11375 1800);
FORCEPROP 1 LAST LOCATION PR368
J 2
(-11420 1925);
DISPLAY 0.489362 (-11420 1925);
PAINT SKYBLUE (-11420 1925);
FORCEPROP 0 LAST $SEC 1
J 2
(-11425 1975);
DISPLAY 0.680851 (-11425 1975);
PAINT MONO (-11425 1975);
DISPLAY INVISIBLE (-11425 1975);
FORCEPROP 0 LAST CDS_SEC 1
J 2
(-11425 1975);
DISPLAY 1.021277 (-11425 1975);
DISPLAY INVISIBLE (-11425 1975);
FORCEPROP 1 LASTPIN (-11375 1900) $PN 1
J 2
(-11380 1862);
DISPLAY 0.489362 (-11380 1862);
PAINT MONO (-11380 1862);
FORCEPROP 1 LASTPIN (-11375 1700) $PN 2
J 2
(-11380 1710);
DISPLAY 0.489362 (-11380 1710);
PAINT MONO (-11380 1710);
FORCEPROP 1 LAST PACK_TYPE 0402LF
J 2
(-11425 1625);
DISPLAY 0.489362 (-11425 1625);
PAINT SKYBLUE (-11425 1625);
FORCEPROP 1 LAST VALUE 8.87K
J 2
(-11430 1875);
DISPLAY 0.489362 (-11430 1875);
PAINT SKYBLUE (-11430 1875);
FORCEPROP 1 LAST TOLERANCE 1%
J 2
(-11430 1825);
DISPLAY 0.489362 (-11430 1825);
PAINT SKYBLUE (-11430 1825);
FORCEPROP 1 LAST MATERIAL EMPTY
J 2
(-11425 1725);
DISPLAY 0.489362 (-11425 1725);
PAINT RED (-11425 1725);
FORCEPROP 1 LAST WATTAGE 1/16W
J 2
(-11425 1775);
DISPLAY 0.489362 (-11425 1775);
PAINT SKYBLUE (-11425 1775);
FORCEPROP 2 LAST CDS_LIB pure_quanta
J 2
(-11375 1800);
DISPLAY INVISIBLE (-11375 1800);
FORCEPROP 1 LAST PATH I4
J 2
(-11425 1975);
DISPLAY 0.978723 (-11425 1975);
PAINT WHITE (-11425 1975);
DISPLAY INVISIBLE (-11425 1975);
FORCEPROP 1 LAST PART_NUMBER CS28872FB01
J 2
(-11425 1675);
DISPLAY 0.489362 (-11425 1675);
PAINT SKYBLUE (-11425 1675);
DISPLAY INVISIBLE (-11425 1675);
FORCEADD UNIVERSAL_GND..1
(-7600 1950);
FORCEPROP 3 LASTPIN (-7600 2000) SIG_NAME GND\g
J 0
(-7590 2010);
DISPLAY 0.659574 (-7590 2010);
PAINT MONO (-7590 2010);
DISPLAY INVISIBLE (-7590 2010);
FORCEPROP 2 LAST CDS_LIB pure_quanta_power
J 0
(-7600 1950);
DISPLAY INVISIBLE (-7600 1950);
FORCEPROP 1 LAST HDL_POWER GND
J 1
(-7575 1875);
DISPLAY 0.872340 (-7575 1875);
PAINT GREEN (-7575 1875);
DISPLAY INVISIBLE (-7575 1875);
FORCEPROP 1 LAST PATH I40
J 0
(-7525 1950);
DISPLAY 0.872340 (-7525 1950);
PAINT AQUA (-7525 1950);
DISPLAY INVISIBLE (-7525 1950);
FORCEADD Q_RES..1
(-6750 1275);
FORCEPROP 1 LAST LOCATION PR375
J 0
(-6775 1325);
DISPLAY 0.489362 (-6775 1325);
PAINT SKYBLUE (-6775 1325);
FORCEPROP 0 LAST $SEC 1
J 0
(-6500 1400);
DISPLAY 0.680851 (-6500 1400);
PAINT MONO (-6500 1400);
DISPLAY INVISIBLE (-6500 1400);
FORCEPROP 0 LAST CDS_SEC 1
J 0
(-6500 1400);
DISPLAY 1.021277 (-6500 1400);
DISPLAY INVISIBLE (-6500 1400);
FORCEPROP 1 LASTPIN (-6850 1275) $PN 1
J 0
(-6838 1287);
DISPLAY 0.787234 (-6838 1287);
PAINT MONO (-6838 1287);
DISPLAY INVISIBLE (-6838 1287);
FORCEPROP 1 LASTPIN (-6650 1275) $PN 2
J 0
(-6688 1287);
DISPLAY 0.787234 (-6688 1287);
PAINT MONO (-6688 1287);
DISPLAY INVISIBLE (-6688 1287);
FORCEPROP 1 LAST WATTAGE 1/16W
J 2
(-6500 1325);
DISPLAY 0.489362 (-6500 1325);
PAINT SKYBLUE (-6500 1325);
FORCEPROP 1 LAST MATERIAL CHIP
J 0
(-6625 1175);
DISPLAY 0.489362 (-6625 1175);
PAINT SKYBLUE (-6625 1175);
FORCEPROP 1 LAST TOLERANCE 5%
J 0
(-6975 1175);
DISPLAY 0.489362 (-6975 1175);
PAINT SKYBLUE (-6975 1175);
FORCEPROP 1 LAST VALUE 0
J 2
(-6925 1325);
DISPLAY 0.489362 (-6925 1325);
PAINT SKYBLUE (-6925 1325);
FORCEPROP 1 LAST PACK_TYPE 0402LF
J 0
(-6650 1225);
DISPLAY 0.489362 (-6650 1225);
PAINT SKYBLUE (-6650 1225);
FORCEPROP 2 LAST CDS_LIB pure_quanta
J 0
(-6750 1275);
DISPLAY INVISIBLE (-6750 1275);
FORCEPROP 1 LAST PATH I41
J 0
(-6800 1425);
DISPLAY 0.978723 (-6800 1425);
PAINT WHITE (-6800 1425);
DISPLAY INVISIBLE (-6800 1425);
FORCEPROP 1 LAST PART_NUMBER CS00002JB13
J 0
(-7075 1225);
DISPLAY 0.489362 (-7075 1225);
PAINT SKYBLUE (-7075 1225);
DISPLAY INVISIBLE (-7075 1225);
FORCEADD Q_INDUCTOR4P_14..1
(-6275 2175);
FORCEPROP 1 LAST LOCATION PL67
J 0
(-6550 2350);
DISPLAY 0.489362 (-6550 2350);
PAINT SKYBLUE (-6550 2350);
FORCEPROP 0 LAST $SEC 1
J 0
(-6225 2375);
DISPLAY 0.680851 (-6225 2375);
PAINT MONO (-6225 2375);
DISPLAY INVISIBLE (-6225 2375);
FORCEPROP 0 LAST CDS_SEC 1
J 0
(-6225 2375);
DISPLAY 1.021277 (-6225 2375);
DISPLAY INVISIBLE (-6225 2375);
FORCEPROP 0 LASTPIN (-6675 2300) $PN 1
J 2
(-6685 2310);
DISPLAY 0.489362 (-6685 2310);
PAINT MONO (-6685 2310);
FORCEPROP 0 LASTPIN (-6675 2050) $PN 2
J 2
(-6685 2060);
DISPLAY 0.489362 (-6685 2060);
PAINT MONO (-6685 2060);
FORCEPROP 0 LASTPIN (-5875 2050) $PN 3
J 0
(-5865 2060);
DISPLAY 0.489362 (-5865 2060);
PAINT MONO (-5865 2060);
FORCEPROP 0 LASTPIN (-5875 2300) $PN 4
J 0
(-5865 2310);
DISPLAY 0.489362 (-5865 2310);
PAINT MONO (-5865 2310);
FORCEPROP 2 LAST VALUE 150NH
J 0
(-6375 2350);
DISPLAY 0.489362 (-6375 2350);
PAINT SKYBLUE (-6375 2350);
FORCEPROP 1 LAST MATERIAL IND
J 0
(-6475 2350);
DISPLAY 0.489362 (-6475 2350);
PAINT SKYBLUE (-6475 2350);
FORCEPROP 2 LAST PART_TYPE SMLF
J 0
(-6350 1925);
DISPLAY 1.021277 (-6350 1925);
FORCEPROP 1 LAST NEEDS_NO_SIZE TRUE
J 0
(-6275 2175);
DISPLAY 0.468085 (-6275 2175);
PAINT GREEN (-6275 2175);
DISPLAY INVISIBLE (-6275 2175);
FORCEPROP 2 LAST CDS_LIB pure_quanta
J 0
(-6275 2175);
DISPLAY INVISIBLE (-6275 2175);
FORCEPROP 1 LAST PATH I42
J 0
(-6075 2330);
DISPLAY 0.723404 (-6075 2330);
PAINT GREEN (-6075 2330);
DISPLAY INVISIBLE (-6075 2330);
FORCEPROP 1 LAST PART_NUMBER CV+15^0TZ04
J 0
(-6225 2350);
DISPLAY 0.489362 (-6225 2350);
PAINT SKYBLUE (-6225 2350);
DISPLAY INVISIBLE (-6225 2350);
FORCEADD Q_INDUCTOR..1
R 2
(-7300 2075);
FORCEPROP 1 LAST LOCATION PL46
J 2
(-7350 2225);
DISPLAY 0.468085 (-7350 2225);
PAINT SKYBLUE (-7350 2225);
FORCEPROP 0 LAST $SEC 1
J 0
(-7350 2250);
DISPLAY 0.680851 (-7350 2250);
PAINT MONO (-7350 2250);
DISPLAY INVISIBLE (-7350 2250);
FORCEPROP 0 LAST CDS_SEC 1
J 0
(-7500 2250);
DISPLAY 1.021277 (-7500 2250);
DISPLAY INVISIBLE (-7500 2250);
FORCEPROP 0 LASTPIN (-7200 2050) $PN 1
J 0
(-7190 2060);
DISPLAY 0.680851 (-7190 2060);
PAINT MONO (-7190 2060);
FORCEPROP 0 LASTPIN (-7400 2050) $PN 2
J 2
(-7410 2060);
DISPLAY 0.680851 (-7410 2060);
PAINT MONO (-7410 2060);
FORCEPROP 2 LAST PACK_TYPE SMLF
J 0
(-7425 2200);
DISPLAY 0.617021 (-7425 2200);
FORCEPROP 2 LAST VALUE 0.22UH/33A
J 0
(-7425 2175);
DISPLAY 0.489362 (-7425 2175);
PAINT SKYBLUE (-7425 2175);
FORCEPROP 1 LAST MATERIAL IND
J 2
(-7350 2125);
DISPLAY 0.468085 (-7350 2125);
PAINT SKYBLUE (-7350 2125);
FORCEPROP 1 LAST NEEDS_NO_SIZE TRUE
J 2
(-7300 2075);
DISPLAY 0.468085 (-7300 2075);
PAINT GREEN (-7300 2075);
DISPLAY INVISIBLE (-7300 2075);
FORCEPROP 2 LAST CDS_LIB pure_quanta
J 0
(-7300 2075);
DISPLAY INVISIBLE (-7300 2075);
FORCEPROP 1 LAST PATH I43
J 2
(-7375 2130);
DISPLAY 0.723404 (-7375 2130);
PAINT GREEN (-7375 2130);
DISPLAY INVISIBLE (-7375 2130);
FORCEPROP 1 LAST PART_NUMBER CV+22Y0EZ00
J 2
(-7175 2150);
DISPLAY 0.468085 (-7175 2150);
PAINT SKYBLUE (-7175 2150);
DISPLAY INVISIBLE (-7175 2150);
FORCEADD Q_CAP..1
(-7025 2525);
FORCEPROP 1 LAST LOCATION PC630
J 0
(-6975 2625);
DISPLAY 0.489362 (-6975 2625);
PAINT SKYBLUE (-6975 2625);
FORCEPROP 0 LAST $SEC 1
J 0
(-6975 2675);
DISPLAY 0.680851 (-6975 2675);
PAINT MONO (-6975 2675);
DISPLAY INVISIBLE (-6975 2675);
FORCEPROP 0 LAST CDS_SEC 1
J 2
(-6975 2650);
DISPLAY 1.021277 (-6975 2650);
DISPLAY INVISIBLE (-6975 2650);
FORCEPROP 1 LASTPIN (-7025 2625) $PN 1
J 0
(-7015 2605);
DISPLAY 0.489362 (-7015 2605);
PAINT MONO (-7015 2605);
FORCEPROP 1 LASTPIN (-7025 2425) $PN 2
J 0
(-7015 2405);
DISPLAY 0.489362 (-7015 2405);
PAINT MONO (-7015 2405);
FORCEPROP 1 LAST PACK_TYPE 0402
J 0
(-6975 2325);
DISPLAY 0.489362 (-6975 2325);
PAINT SKYBLUE (-6975 2325);
FORCEPROP 1 LAST VOLTAGE 16V
J 0
(-6975 2525);
DISPLAY 0.489362 (-6975 2525);
PAINT SKYBLUE (-6975 2525);
FORCEPROP 1 LAST MATERIAL X7R
J 0
(-6975 2425);
DISPLAY 0.489362 (-6975 2425);
PAINT SKYBLUE (-6975 2425);
FORCEPROP 1 LAST VALUE 0.22UF
J 0
(-6975 2575);
DISPLAY 0.489362 (-6975 2575);
PAINT SKYBLUE (-6975 2575);
FORCEPROP 1 LAST TOLERANCE 10%
J 0
(-6975 2475);
DISPLAY 0.489362 (-6975 2475);
PAINT SKYBLUE (-6975 2475);
FORCEPROP 2 LAST CDS_LIB pure_quanta
J 2
(-7025 2525);
DISPLAY INVISIBLE (-7025 2525);
FORCEPROP 1 LAST PATH I44
J 0
(-6975 2675);
DISPLAY 0.978723 (-6975 2675);
PAINT WHITE (-6975 2675);
DISPLAY INVISIBLE (-6975 2675);
FORCEPROP 1 LAST PART_NUMBER CH4223K1B00
J 0
(-6975 2375);
DISPLAY 0.489362 (-6975 2375);
PAINT SKYBLUE (-6975 2375);
DISPLAY INVISIBLE (-6975 2375);
FORCEADD Q_CAP..1
(-8000 3250);
FORCEPROP 1 LAST LOCATION PC625_4
J 0
(-7950 3400);
DISPLAY 0.489362 (-7950 3400);
PAINT SKYBLUE (-7950 3400);
FORCEPROP 0 LAST $SEC 1
J 0
(-7950 3450);
DISPLAY 0.680851 (-7950 3450);
PAINT MONO (-7950 3450);
DISPLAY INVISIBLE (-7950 3450);
FORCEPROP 0 LAST CDS_SEC 1
J 0
(-7950 3450);
DISPLAY 1.021277 (-7950 3450);
DISPLAY INVISIBLE (-7950 3450);
FORCEPROP 1 LASTPIN (-8000 3350) $PN 1
J 0
(-7990 3330);
DISPLAY 0.489362 (-7990 3330);
PAINT MONO (-7990 3330);
FORCEPROP 1 LASTPIN (-8000 3150) $PN 2
J 0
(-7990 3130);
DISPLAY 0.489362 (-7990 3130);
PAINT MONO (-7990 3130);
FORCEPROP 1 LAST PACK_TYPE C0402
J 0
(-7950 3150);
DISPLAY 0.489362 (-7950 3150);
PAINT SKYBLUE (-7950 3150);
FORCEPROP 1 LAST TOLERANCE 10%
J 0
(-7950 3250);
DISPLAY 0.489362 (-7950 3250);
PAINT SKYBLUE (-7950 3250);
FORCEPROP 1 LAST MATERIAL X6S
J 0
(-7950 3200);
DISPLAY 0.489362 (-7950 3200);
PAINT SKYBLUE (-7950 3200);
FORCEPROP 1 LAST VALUE 1UF
J 0
(-7950 3350);
DISPLAY 0.489362 (-7950 3350);
PAINT SKYBLUE (-7950 3350);
FORCEPROP 1 LAST VOLTAGE 25V
J 0
(-7950 3300);
DISPLAY 0.489362 (-7950 3300);
PAINT SKYBLUE (-7950 3300);
FORCEPROP 2 LAST CDS_LIB pure_quanta
J 0
(-8000 3250);
DISPLAY INVISIBLE (-8000 3250);
FORCEPROP 1 LAST PATH I45
J 0
(-7950 3400);
DISPLAY 0.978723 (-7950 3400);
PAINT WHITE (-7950 3400);
DISPLAY INVISIBLE (-7950 3400);
FORCEPROP 1 LAST PART_NUMBER CH5104KEB02
J 0
(-7950 3100);
DISPLAY 0.489362 (-7950 3100);
PAINT SKYBLUE (-7950 3100);
DISPLAY INVISIBLE (-7950 3100);
FORCEADD Q_CAP..1
(-7200 3250);
FORCEPROP 1 LAST LOCATION PC629_4
J 0
(-7150 3400);
DISPLAY 0.489362 (-7150 3400);
PAINT SKYBLUE (-7150 3400);
FORCEPROP 0 LAST $SEC 1
J 0
(-7150 3450);
DISPLAY 0.680851 (-7150 3450);
PAINT MONO (-7150 3450);
DISPLAY INVISIBLE (-7150 3450);
FORCEPROP 0 LAST CDS_SEC 1
J 0
(-7150 3450);
DISPLAY 1.021277 (-7150 3450);
DISPLAY INVISIBLE (-7150 3450);
FORCEPROP 1 LASTPIN (-7200 3350) $PN 1
J 0
(-7190 3330);
DISPLAY 0.489362 (-7190 3330);
PAINT MONO (-7190 3330);
FORCEPROP 1 LASTPIN (-7200 3150) $PN 2
J 0
(-7190 3130);
DISPLAY 0.489362 (-7190 3130);
PAINT MONO (-7190 3130);
FORCEPROP 1 LAST TOLERANCE 20%
J 0
(-7150 3250);
DISPLAY 0.489362 (-7150 3250);
PAINT SKYBLUE (-7150 3250);
FORCEPROP 1 LAST VOLTAGE 16V
J 0
(-7150 3300);
DISPLAY 0.489362 (-7150 3300);
PAINT SKYBLUE (-7150 3300);
FORCEPROP 1 LAST VALUE 22UF
J 0
(-7150 3350);
DISPLAY 0.489362 (-7150 3350);
PAINT SKYBLUE (-7150 3350);
FORCEPROP 1 LAST MATERIAL X6S
J 0
(-7150 3200);
DISPLAY 0.489362 (-7150 3200);
PAINT SKYBLUE (-7150 3200);
FORCEPROP 1 LAST PACK_TYPE C0805
J 0
(-7150 3150);
DISPLAY 0.489362 (-7150 3150);
PAINT SKYBLUE (-7150 3150);
FORCEPROP 2 LAST CDS_LIB pure_quanta
J 0
(-7200 3250);
DISPLAY INVISIBLE (-7200 3250);
FORCEPROP 1 LAST PATH I46
J 0
(-7150 3400);
DISPLAY 0.978723 (-7150 3400);
PAINT WHITE (-7150 3400);
DISPLAY INVISIBLE (-7150 3400);
FORCEPROP 1 LAST PART_NUMBER CH6223MEA01
J 0
(-7150 3100);
DISPLAY 0.489362 (-7150 3100);
PAINT SKYBLUE (-7150 3100);
DISPLAY INVISIBLE (-7150 3100);
FORCEADD UNIVERSAL_GND..1
(-6725 2875);
FORCEPROP 3 LASTPIN (-6725 2925) SIG_NAME GND\g
J 0
(-6715 2935);
DISPLAY 0.659574 (-6715 2935);
PAINT MONO (-6715 2935);
DISPLAY INVISIBLE (-6715 2935);
FORCEPROP 2 LAST CDS_LIB pure_quanta_power
J 0
(-6725 2875);
PAINT MONO (-6725 2875);
DISPLAY INVISIBLE (-6725 2875);
FORCEPROP 1 LAST HDL_POWER GND
J 1
(-6700 2800);
DISPLAY 0.872340 (-6700 2800);
PAINT GREEN (-6700 2800);
DISPLAY INVISIBLE (-6700 2800);
FORCEPROP 1 LAST PATH I47
J 0
(-6650 2875);
DISPLAY 0.872340 (-6650 2875);
PAINT AQUA (-6650 2875);
DISPLAY INVISIBLE (-6650 2875);
FORCEADD Q_CAP..1
(-6725 3250);
FORCEPROP 1 LAST LOCATION PC633_4
J 0
(-6675 3350);
DISPLAY 0.489362 (-6675 3350);
PAINT SKYBLUE (-6675 3350);
FORCEPROP 0 LAST $SEC 1
J 0
(-6675 3400);
DISPLAY 0.680851 (-6675 3400);
PAINT MONO (-6675 3400);
DISPLAY INVISIBLE (-6675 3400);
FORCEPROP 0 LAST CDS_SEC 1
J 0
(-6675 3400);
DISPLAY 1.021277 (-6675 3400);
DISPLAY INVISIBLE (-6675 3400);
FORCEPROP 1 LASTPIN (-6725 3350) $PN 1
J 0
(-6715 3330);
DISPLAY 0.489362 (-6715 3330);
PAINT MONO (-6715 3330);
FORCEPROP 1 LASTPIN (-6725 3150) $PN 2
J 0
(-6715 3130);
DISPLAY 0.489362 (-6715 3130);
PAINT MONO (-6715 3130);
FORCEPROP 1 LAST TOLERANCE 20%
J 0
(-6675 3200);
DISPLAY 0.489362 (-6675 3200);
PAINT SKYBLUE (-6675 3200);
FORCEPROP 1 LAST VOLTAGE 16V
J 0
(-6675 3250);
DISPLAY 0.489362 (-6675 3250);
PAINT SKYBLUE (-6675 3250);
FORCEPROP 1 LAST VALUE 22UF
J 0
(-6675 3300);
DISPLAY 0.489362 (-6675 3300);
PAINT SKYBLUE (-6675 3300);
FORCEPROP 1 LAST MATERIAL X6S
J 0
(-6675 3150);
DISPLAY 0.489362 (-6675 3150);
PAINT SKYBLUE (-6675 3150);
FORCEPROP 1 LAST PACK_TYPE C0805
J 0
(-6675 3050);
DISPLAY 0.489362 (-6675 3050);
PAINT SKYBLUE (-6675 3050);
FORCEPROP 2 LAST CDS_LIB pure_quanta
J 0
(-6725 3250);
DISPLAY INVISIBLE (-6725 3250);
FORCEPROP 1 LAST PATH I48
J 0
(-6675 3400);
DISPLAY 0.978723 (-6675 3400);
PAINT WHITE (-6675 3400);
DISPLAY INVISIBLE (-6675 3400);
FORCEPROP 1 LAST PART_NUMBER CH6223MEA01
J 0
(-6675 3100);
DISPLAY 0.489362 (-6675 3100);
PAINT SKYBLUE (-6675 3100);
DISPLAY INVISIBLE (-6675 3100);
FORCEADD VCC_CORE..1
(-6725 3625);
FORCEPROP 3 LASTPIN (-6725 3575) SIG_NAME SW_P12V_AUX_PVDDIO_P1_FLT\g
J 0
(-6715 3585);
DISPLAY 0.659574 (-6715 3585);
PAINT MONO (-6715 3585);
DISPLAY INVISIBLE (-6715 3585);
FORCEPROP 1 LAST HDL_POWER SW_P12V_AUX_PVDDIO_P1_FLT
J 1
(-6725 3675);
DISPLAY 0.489362 (-6725 3675);
PAINT GREEN (-6725 3675);
FORCEPROP 2 LAST CDS_LIB pure_quanta_power
J 0
(-6725 3625);
DISPLAY INVISIBLE (-6725 3625);
FORCEPROP 1 LAST PATH I49
J 0
(-6675 3650);
DISPLAY 0.872340 (-6675 3650);
PAINT AQUA (-6675 3650);
DISPLAY INVISIBLE (-6675 3650);
FORCEADD OFFPAGE..1
(-10900 1700);
FORCEPROP 2 LAST $XR0 217 
J 0
(-11182 1700);
DISPLAY 0.638298 (-11182 1700);
PAINT MONO (-11182 1700);
FORCEPROP 2 LAST CDS_LIB standard
J 0
(-10900 1700);
DISPLAY INVISIBLE (-10900 1700);
FORCEPROP 1 LAST OFFPAGE TRUE
J 0
(-10575 1575);
DISPLAY 0.872340 (-10575 1575);
PAINT GREEN (-10575 1575);
DISPLAY INVISIBLE (-10575 1575);
FORCEPROP 1 LAST COMMENT_BODY TRUE
J 0
(-10775 1600);
DISPLAY 0.872340 (-10775 1600);
PAINT GREEN (-10775 1600);
DISPLAY INVISIBLE (-10775 1600);
FORCEPROP 2 LAST PATH I5
J 0
(-11150 1750);
DISPLAY 0.680851 (-11150 1750);
DISPLAY INVISIBLE (-11150 1750);
FORCEADD OFFPAGE..3
(-5325 2050);
FORCEPROP 2 LAST $XR0 223 
J 0
(-5111 2050);
DISPLAY 0.638298 (-5111 2050);
PAINT MONO (-5111 2050);
FORCEPROP 2 LAST CDS_LIB standard
J 0
(-5325 2050);
DISPLAY INVISIBLE (-5325 2050);
FORCEPROP 1 LAST OFFPAGE TRUE
J 0
(-5000 1925);
DISPLAY 0.872340 (-5000 1925);
PAINT GREEN (-5000 1925);
DISPLAY INVISIBLE (-5000 1925);
FORCEPROP 1 LAST COMMENT_BODY TRUE
J 0
(-5375 1950);
DISPLAY 0.872340 (-5375 1950);
PAINT GREEN (-5375 1950);
DISPLAY INVISIBLE (-5375 1950);
FORCEPROP 2 LAST PATH I50
J 0
(-5100 2100);
DISPLAY 0.680851 (-5100 2100);
DISPLAY INVISIBLE (-5100 2100);
FORCEADD Q_CAP..1
(-4475 2100);
FORCEPROP 1 LAST LOCATION PC634_4
J 0
(-4425 2225);
DISPLAY 0.489362 (-4425 2225);
PAINT SKYBLUE (-4425 2225);
FORCEPROP 0 LAST $SEC 1
J 0
(-4425 2275);
DISPLAY 0.680851 (-4425 2275);
PAINT MONO (-4425 2275);
DISPLAY INVISIBLE (-4425 2275);
FORCEPROP 0 LAST CDS_SEC 1
J 0
(-4425 2275);
DISPLAY 1.021277 (-4425 2275);
DISPLAY INVISIBLE (-4425 2275);
FORCEPROP 1 LASTPIN (-4475 2200) $PN 1
J 0
(-4465 2180);
DISPLAY 0.489362 (-4465 2180);
PAINT MONO (-4465 2180);
FORCEPROP 1 LASTPIN (-4475 2000) $PN 2
J 0
(-4465 1980);
DISPLAY 0.489362 (-4465 1980);
PAINT MONO (-4465 1980);
FORCEPROP 1 LAST PACK_TYPE C0805
J 0
(-4425 1975);
DISPLAY 0.489362 (-4425 1975);
PAINT SKYBLUE (-4425 1975);
FORCEPROP 1 LAST MATERIAL X6S
J 0
(-4425 2025);
DISPLAY 0.489362 (-4425 2025);
PAINT SKYBLUE (-4425 2025);
FORCEPROP 1 LAST TOLERANCE 20%
J 0
(-4425 2075);
DISPLAY 0.489362 (-4425 2075);
PAINT SKYBLUE (-4425 2075);
FORCEPROP 1 LAST VALUE 22UF
J 0
(-4425 2175);
DISPLAY 0.489362 (-4425 2175);
PAINT SKYBLUE (-4425 2175);
FORCEPROP 1 LAST VOLTAGE 4V
J 0
(-4425 2125);
DISPLAY 0.489362 (-4425 2125);
PAINT SKYBLUE (-4425 2125);
FORCEPROP 2 LAST CDS_LIB pure_quanta
J 0
(-4475 2100);
DISPLAY INVISIBLE (-4475 2100);
FORCEPROP 1 LAST PATH I51
J 0
(-4425 2250);
DISPLAY 0.978723 (-4425 2250);
PAINT WHITE (-4425 2250);
DISPLAY INVISIBLE (-4425 2250);
FORCEPROP 1 LAST PART_NUMBER CH622KMEA03
J 0
(-4425 1925);
DISPLAY 0.489362 (-4425 1925);
PAINT SKYBLUE (-4425 1925);
DISPLAY INVISIBLE (-4425 1925);
FORCEADD UNIVERSAL_GND..1
(-4050 1750);
FORCEPROP 3 LASTPIN (-4050 1800) SIG_NAME GND\g
J 0
(-4040 1810);
DISPLAY 0.659574 (-4040 1810);
PAINT MONO (-4040 1810);
DISPLAY INVISIBLE (-4040 1810);
FORCEPROP 2 LAST CDS_LIB pure_quanta_power
J 0
(-4050 1750);
PAINT MONO (-4050 1750);
DISPLAY INVISIBLE (-4050 1750);
FORCEPROP 1 LAST HDL_POWER GND
J 1
(-4025 1675);
DISPLAY 0.872340 (-4025 1675);
PAINT GREEN (-4025 1675);
DISPLAY INVISIBLE (-4025 1675);
FORCEPROP 1 LAST PATH I52
J 0
(-3975 1750);
DISPLAY 0.872340 (-3975 1750);
PAINT AQUA (-3975 1750);
DISPLAY INVISIBLE (-3975 1750);
FORCEADD Q_CAP..1
(-4050 2100);
FORCEPROP 1 LAST LOCATION PC636_4
J 0
(-4000 2225);
DISPLAY 0.489362 (-4000 2225);
PAINT SKYBLUE (-4000 2225);
FORCEPROP 0 LAST $SEC 1
J 0
(-4000 2275);
DISPLAY 0.680851 (-4000 2275);
PAINT MONO (-4000 2275);
DISPLAY INVISIBLE (-4000 2275);
FORCEPROP 0 LAST CDS_SEC 1
J 0
(-4000 2275);
DISPLAY 1.021277 (-4000 2275);
DISPLAY INVISIBLE (-4000 2275);
FORCEPROP 1 LASTPIN (-4050 2200) $PN 1
J 0
(-4040 2180);
DISPLAY 0.489362 (-4040 2180);
PAINT MONO (-4040 2180);
FORCEPROP 1 LASTPIN (-4050 2000) $PN 2
J 0
(-4040 1980);
DISPLAY 0.489362 (-4040 1980);
PAINT MONO (-4040 1980);
FORCEPROP 1 LAST PACK_TYPE C0805
J 0
(-4000 1975);
DISPLAY 0.489362 (-4000 1975);
PAINT SKYBLUE (-4000 1975);
FORCEPROP 1 LAST MATERIAL X6S
J 0
(-4000 2025);
DISPLAY 0.489362 (-4000 2025);
PAINT SKYBLUE (-4000 2025);
FORCEPROP 1 LAST TOLERANCE 20%
J 0
(-4000 2075);
DISPLAY 0.489362 (-4000 2075);
PAINT SKYBLUE (-4000 2075);
FORCEPROP 1 LAST VALUE 22UF
J 0
(-4000 2175);
DISPLAY 0.489362 (-4000 2175);
PAINT SKYBLUE (-4000 2175);
FORCEPROP 1 LAST VOLTAGE 4V
J 0
(-4000 2125);
DISPLAY 0.489362 (-4000 2125);
PAINT SKYBLUE (-4000 2125);
FORCEPROP 2 LAST CDS_LIB pure_quanta
J 0
(-4050 2100);
DISPLAY INVISIBLE (-4050 2100);
FORCEPROP 1 LAST PATH I53
J 0
(-4000 2250);
DISPLAY 0.978723 (-4000 2250);
PAINT WHITE (-4000 2250);
DISPLAY INVISIBLE (-4000 2250);
FORCEPROP 1 LAST PART_NUMBER CH622KMEA03
J 0
(-4000 1925);
DISPLAY 0.489362 (-4000 1925);
PAINT SKYBLUE (-4000 1925);
DISPLAY INVISIBLE (-4000 1925);
FORCEADD VCC_CORE..1
(-4050 2425);
FORCEPROP 3 LASTPIN (-4050 2375) SIG_NAME PVDDIO_P1\g
J 0
(-4040 2385);
DISPLAY 0.659574 (-4040 2385);
PAINT MONO (-4040 2385);
DISPLAY INVISIBLE (-4040 2385);
FORCEPROP 1 LAST HDL_POWER PVDDIO_P1
J 1
(-4050 2475);
DISPLAY 0.489362 (-4050 2475);
PAINT GREEN (-4050 2475);
FORCEPROP 2 LAST CDS_LIB pure_quanta_power
J 0
(-4050 2425);
DISPLAY INVISIBLE (-4050 2425);
FORCEPROP 1 LAST PATH I54
J 0
(-4000 2450);
DISPLAY 0.872340 (-4000 2450);
PAINT AQUA (-4000 2450);
DISPLAY INVISIBLE (-4000 2450);
FORCEADD Q_RES..1
(-6950 4075);
FORCEPROP 1 LAST LOCATION PR374
J 0
(-6975 4125);
DISPLAY 0.489362 (-6975 4125);
PAINT SKYBLUE (-6975 4125);
FORCEPROP 0 LAST $SEC 1
J 0
(-7075 4250);
DISPLAY 0.680851 (-7075 4250);
PAINT MONO (-7075 4250);
DISPLAY INVISIBLE (-7075 4250);
FORCEPROP 0 LAST CDS_SEC 1
J 0
(-7075 4250);
DISPLAY 1.021277 (-7075 4250);
DISPLAY INVISIBLE (-7075 4250);
FORCEPROP 1 LASTPIN (-7050 4075) $PN 1
J 0
(-7038 4087);
DISPLAY 0.787234 (-7038 4087);
PAINT MONO (-7038 4087);
DISPLAY INVISIBLE (-7038 4087);
FORCEPROP 1 LASTPIN (-6850 4075) $PN 2
J 0
(-6888 4087);
DISPLAY 0.787234 (-6888 4087);
PAINT MONO (-6888 4087);
DISPLAY INVISIBLE (-6888 4087);
FORCEPROP 1 LAST WATTAGE 1/16W
J 2
(-6700 4125);
DISPLAY 0.489362 (-6700 4125);
PAINT SKYBLUE (-6700 4125);
FORCEPROP 1 LAST TOLERANCE 5%
J 0
(-7125 3975);
DISPLAY 0.489362 (-7125 3975);
PAINT SKYBLUE (-7125 3975);
FORCEPROP 1 LAST VALUE 0
J 2
(-7150 4125);
DISPLAY 0.489362 (-7150 4125);
PAINT SKYBLUE (-7150 4125);
FORCEPROP 1 LAST PACK_TYPE 0402LF
J 0
(-6850 4025);
DISPLAY 0.489362 (-6850 4025);
PAINT SKYBLUE (-6850 4025);
FORCEPROP 1 LAST MATERIAL CHIP
J 0
(-6825 3975);
DISPLAY 0.489362 (-6825 3975);
PAINT SKYBLUE (-6825 3975);
FORCEPROP 2 LAST CDS_LIB pure_quanta
J 0
(-6950 4075);
DISPLAY INVISIBLE (-6950 4075);
FORCEPROP 1 LAST PATH I55
J 0
(-7000 4225);
DISPLAY 0.978723 (-7000 4225);
PAINT WHITE (-7000 4225);
DISPLAY INVISIBLE (-7000 4225);
FORCEPROP 1 LAST PART_NUMBER CS00002JB13
J 0
(-7250 4025);
DISPLAY 0.489362 (-7250 4025);
PAINT SKYBLUE (-7250 4025);
DISPLAY INVISIBLE (-7250 4025);
FORCEADD UNIVERSAL_GND..1
(-7925 4175);
FORCEPROP 3 LASTPIN (-7925 4225) SIG_NAME GND\g
J 0
(-7915 4235);
DISPLAY 0.659574 (-7915 4235);
PAINT MONO (-7915 4235);
DISPLAY INVISIBLE (-7915 4235);
FORCEPROP 2 LAST CDS_LIB pure_quanta_power
J 0
(-7925 4175);
DISPLAY INVISIBLE (-7925 4175);
FORCEPROP 1 LAST HDL_POWER GND
J 1
(-7900 4100);
DISPLAY 0.872340 (-7900 4100);
PAINT GREEN (-7900 4100);
DISPLAY INVISIBLE (-7900 4100);
FORCEPROP 1 LAST PATH I56
J 0
(-7850 4175);
DISPLAY 0.872340 (-7850 4175);
PAINT AQUA (-7850 4175);
DISPLAY INVISIBLE (-7850 4175);
FORCEADD Q_RES..2
(-7925 4400);
FORCEPROP 1 LAST LOCATION PR492
J 0
(-7880 4525);
DISPLAY 0.489362 (-7880 4525);
PAINT SKYBLUE (-7880 4525);
FORCEPROP 0 LAST $SEC 1
J 0
(-7875 4575);
DISPLAY 0.680851 (-7875 4575);
PAINT MONO (-7875 4575);
DISPLAY INVISIBLE (-7875 4575);
FORCEPROP 0 LAST CDS_SEC 1
J 0
(-7875 4575);
DISPLAY 1.021277 (-7875 4575);
DISPLAY INVISIBLE (-7875 4575);
FORCEPROP 1 LASTPIN (-7925 4500) $PN 1
J 0
(-7920 4462);
DISPLAY 0.489362 (-7920 4462);
PAINT MONO (-7920 4462);
FORCEPROP 1 LASTPIN (-7925 4300) $PN 2
J 0
(-7920 4310);
DISPLAY 0.489362 (-7920 4310);
PAINT MONO (-7920 4310);
FORCEPROP 1 LAST WATTAGE 1/8W
J 0
(-7885 4375);
DISPLAY 0.489362 (-7885 4375);
PAINT SKYBLUE (-7885 4375);
FORCEPROP 1 LAST MATERIAL EMPTY
J 0
(-7885 4325);
DISPLAY 0.489362 (-7885 4325);
PAINT RED (-7885 4325);
FORCEPROP 1 LAST TOLERANCE 1%
J 0
(-7880 4425);
DISPLAY 0.489362 (-7880 4425);
PAINT SKYBLUE (-7880 4425);
FORCEPROP 1 LAST VALUE 1.5
J 0
(-7880 4475);
DISPLAY 0.489362 (-7880 4475);
PAINT SKYBLUE (-7880 4475);
FORCEPROP 1 LAST PACK_TYPE 0402LF
J 0
(-7885 4225);
DISPLAY 0.489362 (-7885 4225);
PAINT SKYBLUE (-7885 4225);
FORCEPROP 2 LAST CDS_LIB pure_quanta
J 0
(-7925 4400);
DISPLAY INVISIBLE (-7925 4400);
FORCEPROP 1 LAST PATH I57
J 0
(-7875 4575);
DISPLAY 0.978723 (-7875 4575);
PAINT WHITE (-7875 4575);
DISPLAY INVISIBLE (-7875 4575);
FORCEPROP 1 LAST PART_NUMBER CS-1504FB00
J 0
(-7885 4275);
DISPLAY 0.489362 (-7885 4275);
PAINT SKYBLUE (-7885 4275);
DISPLAY INVISIBLE (-7885 4275);
FORCEADD Q_CAP..1
(-7925 4900);
FORCEPROP 1 LAST LOCATION PC177
J 0
(-7875 5000);
DISPLAY 0.489362 (-7875 5000);
PAINT SKYBLUE (-7875 5000);
FORCEPROP 0 LAST $SEC 1
J 0
(-7875 5050);
DISPLAY 0.680851 (-7875 5050);
PAINT MONO (-7875 5050);
DISPLAY INVISIBLE (-7875 5050);
FORCEPROP 0 LAST CDS_SEC 1
J 0
(-7875 5050);
DISPLAY 1.021277 (-7875 5050);
DISPLAY INVISIBLE (-7875 5050);
FORCEPROP 1 LASTPIN (-7925 5000) $PN 1
J 0
(-7915 4980);
DISPLAY 0.489362 (-7915 4980);
PAINT MONO (-7915 4980);
FORCEPROP 1 LASTPIN (-7925 4800) $PN 2
J 0
(-7915 4780);
DISPLAY 0.489362 (-7915 4780);
PAINT MONO (-7915 4780);
FORCEPROP 1 LAST VOLTAGE 50V
J 0
(-7875 4900);
DISPLAY 0.489362 (-7875 4900);
PAINT SKYBLUE (-7875 4900);
FORCEPROP 1 LAST VALUE 560PF
J 0
(-7875 4950);
DISPLAY 0.489362 (-7875 4950);
PAINT SKYBLUE (-7875 4950);
FORCEPROP 1 LAST TOLERANCE 10%
J 0
(-7875 4850);
DISPLAY 0.489362 (-7875 4850);
PAINT SKYBLUE (-7875 4850);
FORCEPROP 1 LAST MATERIAL EMPTY
J 0
(-7875 4800);
DISPLAY 0.489362 (-7875 4800);
PAINT RED (-7875 4800);
FORCEPROP 1 LAST PACK_TYPE C0402
J 0
(-7875 4700);
DISPLAY 0.489362 (-7875 4700);
PAINT SKYBLUE (-7875 4700);
FORCEPROP 2 LAST CDS_LIB pure_quanta
J 0
(-7925 4900);
DISPLAY INVISIBLE (-7925 4900);
FORCEPROP 1 LAST PATH I58
J 0
(-7875 5050);
DISPLAY 0.978723 (-7875 5050);
PAINT WHITE (-7875 5050);
DISPLAY INVISIBLE (-7875 5050);
FORCEPROP 1 LAST PART_NUMBER CH1566K1B09
J 0
(-7875 4750);
DISPLAY 0.489362 (-7875 4750);
PAINT SKYBLUE (-7875 4750);
DISPLAY INVISIBLE (-7875 4750);
FORCEADD OFFPAGE..6
(-7050 4850);
FORCEPROP 2 LAST $XR0 223 
J 0
(-7330 4850);
DISPLAY 0.638298 (-7330 4850);
PAINT MONO (-7330 4850);
FORCEPROP 2 LAST CDS_LIB standard
J 0
(-7050 4850);
DISPLAY INVISIBLE (-7050 4850);
FORCEPROP 1 LAST OFFPAGE TRUE
J 0
(-6725 4725);
DISPLAY 0.872340 (-6725 4725);
PAINT GREEN (-6725 4725);
DISPLAY INVISIBLE (-6725 4725);
FORCEPROP 1 LAST COMMENT_BODY TRUE
J 0
(-6950 4775);
DISPLAY 0.872340 (-6950 4775);
PAINT GREEN (-6950 4775);
DISPLAY INVISIBLE (-6950 4775);
FORCEPROP 2 LAST PATH I59
J 0
(-7350 4900);
DISPLAY 0.680851 (-7350 4900);
DISPLAY INVISIBLE (-7350 4900);
FORCEADD OFFPAGE..5
(-10900 1800);
FORCEPROP 2 LAST $XR2 217 
J 0
(-11155 1836);
DISPLAY 0.638298 (-11155 1836);
PAINT MONO (-11155 1836);
FORCEPROP 2 LAST $XR1 223 
J 0
(-11155 1764);
DISPLAY 0.638298 (-11155 1764);
PAINT MONO (-11155 1764);
FORCEPROP 2 LAST $XR0 222 
J 0
(-11155 1800);
DISPLAY 0.638298 (-11155 1800);
PAINT MONO (-11155 1800);
FORCEPROP 2 LAST CDS_LIB standard
J 0
(-10900 1800);
DISPLAY INVISIBLE (-10900 1800);
FORCEPROP 1 LAST OFFPAGE TRUE
J 0
(-10575 1675);
DISPLAY 0.872340 (-10575 1675);
PAINT GREEN (-10575 1675);
DISPLAY INVISIBLE (-10575 1675);
FORCEPROP 1 LAST COMMENT_BODY TRUE
J 0
(-10800 1725);
DISPLAY 0.872340 (-10800 1725);
PAINT GREEN (-10800 1725);
DISPLAY INVISIBLE (-10800 1725);
FORCEPROP 2 LAST PATH I6
J 0
(-11175 1875);
DISPLAY 0.680851 (-11175 1875);
DISPLAY INVISIBLE (-11175 1875);
FORCEADD Q_CAP..1
(-7675 6050);
FORCEPROP 1 LAST LOCATION PC626_3
J 0
(-7625 6200);
DISPLAY 0.489362 (-7625 6200);
PAINT SKYBLUE (-7625 6200);
FORCEPROP 0 LAST $SEC 1
J 0
(-7625 6250);
DISPLAY 0.680851 (-7625 6250);
PAINT MONO (-7625 6250);
DISPLAY INVISIBLE (-7625 6250);
FORCEPROP 0 LAST CDS_SEC 1
J 0
(-7625 6250);
DISPLAY 1.021277 (-7625 6250);
DISPLAY INVISIBLE (-7625 6250);
FORCEPROP 1 LASTPIN (-7675 6150) $PN 1
J 0
(-7665 6130);
DISPLAY 0.489362 (-7665 6130);
PAINT MONO (-7665 6130);
FORCEPROP 1 LASTPIN (-7675 5950) $PN 2
J 0
(-7665 5930);
DISPLAY 0.489362 (-7665 5930);
PAINT MONO (-7665 5930);
FORCEPROP 1 LAST TOLERANCE 20%
J 0
(-7625 6050);
DISPLAY 0.489362 (-7625 6050);
PAINT SKYBLUE (-7625 6050);
FORCEPROP 1 LAST VOLTAGE 16V
J 0
(-7625 6100);
DISPLAY 0.489362 (-7625 6100);
PAINT SKYBLUE (-7625 6100);
FORCEPROP 1 LAST VALUE 22UF
J 0
(-7625 6150);
DISPLAY 0.489362 (-7625 6150);
PAINT SKYBLUE (-7625 6150);
FORCEPROP 1 LAST MATERIAL X6S
J 0
(-7625 6000);
DISPLAY 0.489362 (-7625 6000);
PAINT SKYBLUE (-7625 6000);
FORCEPROP 1 LAST PACK_TYPE C0805
J 0
(-7625 5950);
DISPLAY 0.489362 (-7625 5950);
PAINT SKYBLUE (-7625 5950);
FORCEPROP 2 LAST CDS_LIB pure_quanta
J 0
(-7675 6050);
DISPLAY INVISIBLE (-7675 6050);
FORCEPROP 1 LAST PATH I60
J 0
(-7625 6200);
DISPLAY 0.978723 (-7625 6200);
PAINT WHITE (-7625 6200);
DISPLAY INVISIBLE (-7625 6200);
FORCEPROP 1 LAST PART_NUMBER CH6223MEA01
J 0
(-7625 5900);
DISPLAY 0.489362 (-7625 5900);
PAINT SKYBLUE (-7625 5900);
DISPLAY INVISIBLE (-7625 5900);
FORCEADD Q_CAP..1
(-7275 6050);
FORCEPROP 1 LAST LOCATION PC628_3
J 0
(-7225 6200);
DISPLAY 0.489362 (-7225 6200);
PAINT SKYBLUE (-7225 6200);
FORCEPROP 0 LAST $SEC 1
J 0
(-7225 6250);
DISPLAY 0.680851 (-7225 6250);
PAINT MONO (-7225 6250);
DISPLAY INVISIBLE (-7225 6250);
FORCEPROP 0 LAST CDS_SEC 1
J 0
(-7225 6250);
DISPLAY 1.021277 (-7225 6250);
DISPLAY INVISIBLE (-7225 6250);
FORCEPROP 1 LASTPIN (-7275 6150) $PN 1
J 0
(-7265 6130);
DISPLAY 0.489362 (-7265 6130);
PAINT MONO (-7265 6130);
FORCEPROP 1 LASTPIN (-7275 5950) $PN 2
J 0
(-7265 5930);
DISPLAY 0.489362 (-7265 5930);
PAINT MONO (-7265 5930);
FORCEPROP 1 LAST TOLERANCE 20%
J 0
(-7225 6050);
DISPLAY 0.489362 (-7225 6050);
PAINT SKYBLUE (-7225 6050);
FORCEPROP 1 LAST VOLTAGE 16V
J 0
(-7225 6100);
DISPLAY 0.489362 (-7225 6100);
PAINT SKYBLUE (-7225 6100);
FORCEPROP 1 LAST VALUE 22UF
J 0
(-7225 6150);
DISPLAY 0.489362 (-7225 6150);
PAINT SKYBLUE (-7225 6150);
FORCEPROP 1 LAST MATERIAL X6S
J 0
(-7225 6000);
DISPLAY 0.489362 (-7225 6000);
PAINT SKYBLUE (-7225 6000);
FORCEPROP 1 LAST PACK_TYPE C0805
J 0
(-7225 5950);
DISPLAY 0.489362 (-7225 5950);
PAINT SKYBLUE (-7225 5950);
FORCEPROP 2 LAST CDS_LIB pure_quanta
J 0
(-7275 6050);
DISPLAY INVISIBLE (-7275 6050);
FORCEPROP 1 LAST PATH I61
J 0
(-7225 6200);
DISPLAY 0.978723 (-7225 6200);
PAINT WHITE (-7225 6200);
DISPLAY INVISIBLE (-7225 6200);
FORCEPROP 1 LAST PART_NUMBER CH6223MEA01
J 0
(-7225 5900);
DISPLAY 0.489362 (-7225 5900);
PAINT SKYBLUE (-7225 5900);
DISPLAY INVISIBLE (-7225 5900);
FORCEADD Q_INDUCTOR4P_14..1
(-6025 4975);
FORCEPROP 1 LAST LOCATION PL68
J 0
(-6250 5230);
DISPLAY 0.489362 (-6250 5230);
PAINT SKYBLUE (-6250 5230);
FORCEPROP 0 LAST $SEC 1
J 0
(-5950 5300);
DISPLAY 0.680851 (-5950 5300);
PAINT MONO (-5950 5300);
DISPLAY INVISIBLE (-5950 5300);
FORCEPROP 0 LAST CDS_SEC 1
J 0
(-5950 5300);
DISPLAY 1.021277 (-5950 5300);
DISPLAY INVISIBLE (-5950 5300);
FORCEPROP 0 LASTPIN (-6425 5100) $PN 1
J 2
(-6435 5110);
DISPLAY 0.489362 (-6435 5110);
PAINT MONO (-6435 5110);
FORCEPROP 0 LASTPIN (-6425 4850) $PN 2
J 2
(-6435 4860);
DISPLAY 0.489362 (-6435 4860);
PAINT MONO (-6435 4860);
FORCEPROP 0 LASTPIN (-5625 4850) $PN 3
J 0
(-5615 4860);
DISPLAY 0.489362 (-5615 4860);
PAINT MONO (-5615 4860);
FORCEPROP 0 LASTPIN (-5625 5100) $PN 4
J 0
(-5615 5110);
DISPLAY 0.489362 (-5615 5110);
PAINT MONO (-5615 5110);
FORCEPROP 1 LAST MATERIAL IND
J 0
(-6225 5150);
DISPLAY 0.489362 (-6225 5150);
PAINT SKYBLUE (-6225 5150);
FORCEPROP 2 LAST VALUE 150NH
J 0
(-6125 5150);
DISPLAY 0.489362 (-6125 5150);
PAINT SKYBLUE (-6125 5150);
FORCEPROP 2 LAST PART_TYPE SMLF
J 0
(-5950 5250);
DISPLAY 1.021277 (-5950 5250);
FORCEPROP 2 LAST CDS_LIB pure_quanta
J 0
(-6025 4975);
DISPLAY INVISIBLE (-6025 4975);
FORCEPROP 1 LAST NEEDS_NO_SIZE TRUE
J 0
(-6025 4975);
DISPLAY 0.468085 (-6025 4975);
PAINT GREEN (-6025 4975);
DISPLAY INVISIBLE (-6025 4975);
FORCEPROP 1 LAST PATH I62
J 0
(-5825 5130);
DISPLAY 0.723404 (-5825 5130);
PAINT GREEN (-5825 5130);
DISPLAY INVISIBLE (-5825 5130);
FORCEPROP 1 LAST PART_NUMBER CV+15^0TZ04
J 0
(-5975 5150);
DISPLAY 0.489362 (-5975 5150);
PAINT SKYBLUE (-5975 5150);
DISPLAY INVISIBLE (-5975 5150);
FORCEADD Q_CAP..1
(-6950 5325);
FORCEPROP 1 LAST LOCATION PC631
J 0
(-6900 5425);
DISPLAY 0.489362 (-6900 5425);
PAINT SKYBLUE (-6900 5425);
FORCEPROP 0 LAST $SEC 1
J 0
(-6900 5475);
DISPLAY 0.680851 (-6900 5475);
PAINT MONO (-6900 5475);
DISPLAY INVISIBLE (-6900 5475);
FORCEPROP 0 LAST CDS_SEC 1
J 0
(-6900 5475);
DISPLAY 1.021277 (-6900 5475);
DISPLAY INVISIBLE (-6900 5475);
FORCEPROP 1 LASTPIN (-6950 5425) $PN 1
J 0
(-6940 5405);
DISPLAY 0.489362 (-6940 5405);
PAINT MONO (-6940 5405);
FORCEPROP 1 LASTPIN (-6950 5225) $PN 2
J 0
(-6940 5205);
DISPLAY 0.489362 (-6940 5205);
PAINT MONO (-6940 5205);
FORCEPROP 1 LAST VALUE 0.22UF
J 0
(-6900 5375);
DISPLAY 0.489362 (-6900 5375);
PAINT SKYBLUE (-6900 5375);
FORCEPROP 1 LAST PACK_TYPE 0402
J 0
(-6900 5125);
DISPLAY 0.489362 (-6900 5125);
PAINT SKYBLUE (-6900 5125);
FORCEPROP 1 LAST VOLTAGE 16V
J 0
(-6900 5325);
DISPLAY 0.489362 (-6900 5325);
PAINT SKYBLUE (-6900 5325);
FORCEPROP 1 LAST TOLERANCE 10%
J 0
(-6900 5275);
DISPLAY 0.489362 (-6900 5275);
PAINT SKYBLUE (-6900 5275);
FORCEPROP 1 LAST MATERIAL X7R
J 0
(-6900 5225);
DISPLAY 0.489362 (-6900 5225);
PAINT SKYBLUE (-6900 5225);
FORCEPROP 2 LAST CDS_LIB pure_quanta
J 0
(-6950 5325);
PAINT MONO (-6950 5325);
DISPLAY INVISIBLE (-6950 5325);
FORCEPROP 1 LAST PATH I63
J 0
(-6900 5475);
DISPLAY 0.978723 (-6900 5475);
PAINT WHITE (-6900 5475);
DISPLAY INVISIBLE (-6900 5475);
FORCEPROP 1 LAST PART_NUMBER CH4223K1B00
J 0
(-6900 5175);
DISPLAY 0.489362 (-6900 5175);
PAINT SKYBLUE (-6900 5175);
DISPLAY INVISIBLE (-6900 5175);
FORCEADD UNIVERSAL_GND..1
(-6850 5675);
FORCEPROP 3 LASTPIN (-6850 5725) SIG_NAME GND\g
J 0
(-6840 5735);
DISPLAY 0.659574 (-6840 5735);
PAINT MONO (-6840 5735);
DISPLAY INVISIBLE (-6840 5735);
FORCEPROP 2 LAST CDS_LIB pure_quanta_power
J 0
(-6850 5675);
PAINT MONO (-6850 5675);
DISPLAY INVISIBLE (-6850 5675);
FORCEPROP 1 LAST HDL_POWER GND
J 1
(-6825 5600);
DISPLAY 0.872340 (-6825 5600);
PAINT GREEN (-6825 5600);
DISPLAY INVISIBLE (-6825 5600);
FORCEPROP 1 LAST PATH I64
J 0
(-6775 5675);
DISPLAY 0.872340 (-6775 5675);
PAINT AQUA (-6775 5675);
DISPLAY INVISIBLE (-6775 5675);
FORCEADD Q_CAP..1
(-6850 6075);
FORCEPROP 1 LAST LOCATION PC632_3
J 0
(-6800 6175);
DISPLAY 0.489362 (-6800 6175);
PAINT SKYBLUE (-6800 6175);
FORCEPROP 0 LAST $SEC 1
J 0
(-6800 6225);
DISPLAY 0.680851 (-6800 6225);
PAINT MONO (-6800 6225);
DISPLAY INVISIBLE (-6800 6225);
FORCEPROP 0 LAST CDS_SEC 1
J 0
(-6800 6225);
DISPLAY 1.021277 (-6800 6225);
DISPLAY INVISIBLE (-6800 6225);
FORCEPROP 1 LASTPIN (-6850 6175) $PN 1
J 0
(-6840 6155);
DISPLAY 0.489362 (-6840 6155);
PAINT MONO (-6840 6155);
FORCEPROP 1 LASTPIN (-6850 5975) $PN 2
J 0
(-6840 5955);
DISPLAY 0.489362 (-6840 5955);
PAINT MONO (-6840 5955);
FORCEPROP 1 LAST TOLERANCE 20%
J 0
(-6800 6025);
DISPLAY 0.489362 (-6800 6025);
PAINT SKYBLUE (-6800 6025);
FORCEPROP 1 LAST VOLTAGE 16V
J 0
(-6800 6075);
DISPLAY 0.489362 (-6800 6075);
PAINT SKYBLUE (-6800 6075);
FORCEPROP 1 LAST VALUE 22UF
J 0
(-6800 6125);
DISPLAY 0.489362 (-6800 6125);
PAINT SKYBLUE (-6800 6125);
FORCEPROP 1 LAST MATERIAL X6S
J 0
(-6800 5975);
DISPLAY 0.489362 (-6800 5975);
PAINT SKYBLUE (-6800 5975);
FORCEPROP 1 LAST PACK_TYPE C0805
J 0
(-6800 5875);
DISPLAY 0.489362 (-6800 5875);
PAINT SKYBLUE (-6800 5875);
FORCEPROP 2 LAST CDS_LIB pure_quanta
J 0
(-6850 6075);
DISPLAY INVISIBLE (-6850 6075);
FORCEPROP 1 LAST PATH I65
J 0
(-6800 6225);
DISPLAY 0.978723 (-6800 6225);
PAINT WHITE (-6800 6225);
DISPLAY INVISIBLE (-6800 6225);
FORCEPROP 1 LAST PART_NUMBER CH6223MEA01
J 0
(-6800 5925);
DISPLAY 0.489362 (-6800 5925);
PAINT SKYBLUE (-6800 5925);
DISPLAY INVISIBLE (-6800 5925);
FORCEADD VCC_CORE..1
(-6850 6425);
FORCEPROP 3 LASTPIN (-6850 6375) SIG_NAME SW_P12V_AUX_PVDDIO_P1_FLT\g
J 0
(-6840 6385);
DISPLAY 0.659574 (-6840 6385);
PAINT MONO (-6840 6385);
DISPLAY INVISIBLE (-6840 6385);
FORCEPROP 1 LAST HDL_POWER SW_P12V_AUX_PVDDIO_P1_FLT
J 1
(-6850 6475);
DISPLAY 0.489362 (-6850 6475);
PAINT GREEN (-6850 6475);
FORCEPROP 2 LAST CDS_LIB pure_quanta_power
J 0
(-6850 6425);
DISPLAY INVISIBLE (-6850 6425);
FORCEPROP 1 LAST PATH I66
J 0
(-6800 6450);
DISPLAY 0.872340 (-6800 6450);
PAINT AQUA (-6800 6450);
DISPLAY INVISIBLE (-6800 6450);
FORCEADD OFFPAGE..3
(-4950 4850);
FORCEPROP 2 LAST $XR0 222 
J 0
(-4736 4850);
DISPLAY 0.638298 (-4736 4850);
PAINT MONO (-4736 4850);
FORCEPROP 2 LAST CDS_LIB standard
J 0
(-4950 4850);
DISPLAY INVISIBLE (-4950 4850);
FORCEPROP 1 LAST OFFPAGE TRUE
J 0
(-4625 4725);
DISPLAY 0.872340 (-4625 4725);
PAINT GREEN (-4625 4725);
DISPLAY INVISIBLE (-4625 4725);
FORCEPROP 1 LAST COMMENT_BODY TRUE
J 0
(-5000 4750);
DISPLAY 0.872340 (-5000 4750);
PAINT GREEN (-5000 4750);
DISPLAY INVISIBLE (-5000 4750);
FORCEPROP 2 LAST PATH I67
J 0
(-4725 4900);
DISPLAY 0.680851 (-4725 4900);
DISPLAY INVISIBLE (-4725 4900);
FORCEADD Q_CAP..1
(-4150 4900);
FORCEPROP 1 LAST LOCATION PC635_3
J 0
(-4100 5025);
DISPLAY 0.489362 (-4100 5025);
PAINT SKYBLUE (-4100 5025);
FORCEPROP 0 LAST $SEC 1
J 0
(-4100 5075);
DISPLAY 0.680851 (-4100 5075);
PAINT MONO (-4100 5075);
DISPLAY INVISIBLE (-4100 5075);
FORCEPROP 0 LAST CDS_SEC 1
J 0
(-4100 5075);
DISPLAY 1.021277 (-4100 5075);
DISPLAY INVISIBLE (-4100 5075);
FORCEPROP 1 LASTPIN (-4150 5000) $PN 1
J 0
(-4140 4980);
DISPLAY 0.489362 (-4140 4980);
PAINT MONO (-4140 4980);
FORCEPROP 1 LASTPIN (-4150 4800) $PN 2
J 0
(-4140 4780);
DISPLAY 0.489362 (-4140 4780);
PAINT MONO (-4140 4780);
FORCEPROP 1 LAST PACK_TYPE C0805
J 0
(-4100 4775);
DISPLAY 0.489362 (-4100 4775);
PAINT SKYBLUE (-4100 4775);
FORCEPROP 1 LAST MATERIAL X6S
J 0
(-4100 4825);
DISPLAY 0.489362 (-4100 4825);
PAINT SKYBLUE (-4100 4825);
FORCEPROP 1 LAST TOLERANCE 20%
J 0
(-4100 4875);
DISPLAY 0.489362 (-4100 4875);
PAINT SKYBLUE (-4100 4875);
FORCEPROP 1 LAST VALUE 22UF
J 0
(-4100 4975);
DISPLAY 0.489362 (-4100 4975);
PAINT SKYBLUE (-4100 4975);
FORCEPROP 1 LAST VOLTAGE 4V
J 0
(-4100 4925);
DISPLAY 0.489362 (-4100 4925);
PAINT SKYBLUE (-4100 4925);
FORCEPROP 2 LAST CDS_LIB pure_quanta
J 0
(-4150 4900);
DISPLAY INVISIBLE (-4150 4900);
FORCEPROP 1 LAST PATH I68
J 0
(-4100 5050);
DISPLAY 0.978723 (-4100 5050);
PAINT WHITE (-4100 5050);
DISPLAY INVISIBLE (-4100 5050);
FORCEPROP 1 LAST PART_NUMBER CH622KMEA03
J 0
(-4100 4725);
DISPLAY 0.489362 (-4100 4725);
PAINT SKYBLUE (-4100 4725);
DISPLAY INVISIBLE (-4100 4725);
FORCEADD UNIVERSAL_GND..1
(-3725 4575);
FORCEPROP 3 LASTPIN (-3725 4625) SIG_NAME GND\g
J 0
(-3715 4635);
DISPLAY 0.659574 (-3715 4635);
PAINT MONO (-3715 4635);
DISPLAY INVISIBLE (-3715 4635);
FORCEPROP 2 LAST CDS_LIB pure_quanta_power
J 0
(-3725 4575);
PAINT MONO (-3725 4575);
DISPLAY INVISIBLE (-3725 4575);
FORCEPROP 1 LAST HDL_POWER GND
J 1
(-3700 4500);
DISPLAY 0.872340 (-3700 4500);
PAINT GREEN (-3700 4500);
DISPLAY INVISIBLE (-3700 4500);
FORCEPROP 1 LAST PATH I69
J 0
(-3650 4575);
DISPLAY 0.872340 (-3650 4575);
PAINT AQUA (-3650 4575);
DISPLAY INVISIBLE (-3650 4575);
FORCEADD OFFPAGE..1
(-10900 2200);
FORCEPROP 2 LAST $XR5 223 
J 0
(-11782 2200);
DISPLAY 0.638298 (-11782 2200);
PAINT MONO (-11782 2200);
FORCEPROP 2 LAST $XR4 222 
J 0
(-11662 2200);
DISPLAY 0.638298 (-11662 2200);
PAINT MONO (-11662 2200);
FORCEPROP 2 LAST $XR3 220 
J 0
(-11542 2200);
DISPLAY 0.638298 (-11542 2200);
PAINT MONO (-11542 2200);
FORCEPROP 2 LAST $XR2 219 
J 0
(-11422 2200);
DISPLAY 0.638298 (-11422 2200);
PAINT MONO (-11422 2200);
FORCEPROP 2 LAST $XR1 218 
J 0
(-11302 2200);
DISPLAY 0.638298 (-11302 2200);
PAINT MONO (-11302 2200);
FORCEPROP 2 LAST $XR0 217 
J 0
(-11182 2200);
DISPLAY 0.638298 (-11182 2200);
PAINT MONO (-11182 2200);
FORCEPROP 2 LAST CDS_LIB standard
J 0
(-10900 2200);
DISPLAY INVISIBLE (-10900 2200);
FORCEPROP 1 LAST OFFPAGE TRUE
J 0
(-10575 2075);
DISPLAY 0.872340 (-10575 2075);
PAINT GREEN (-10575 2075);
DISPLAY INVISIBLE (-10575 2075);
FORCEPROP 1 LAST COMMENT_BODY TRUE
J 0
(-10775 2100);
DISPLAY 0.872340 (-10775 2100);
PAINT GREEN (-10775 2100);
DISPLAY INVISIBLE (-10775 2100);
FORCEPROP 2 LAST PATH I7
J 0
(-11150 2250);
DISPLAY 0.680851 (-11150 2250);
DISPLAY INVISIBLE (-11150 2250);
FORCEADD Q_CAP..1
(-3725 4900);
FORCEPROP 1 LAST LOCATION PC637_3
J 0
(-3675 5025);
DISPLAY 0.489362 (-3675 5025);
PAINT SKYBLUE (-3675 5025);
FORCEPROP 0 LAST $SEC 1
J 0
(-3675 5075);
DISPLAY 0.680851 (-3675 5075);
PAINT MONO (-3675 5075);
DISPLAY INVISIBLE (-3675 5075);
FORCEPROP 0 LAST CDS_SEC 1
J 0
(-3675 5075);
DISPLAY 1.021277 (-3675 5075);
DISPLAY INVISIBLE (-3675 5075);
FORCEPROP 1 LASTPIN (-3725 5000) $PN 1
J 0
(-3715 4980);
DISPLAY 0.489362 (-3715 4980);
PAINT MONO (-3715 4980);
FORCEPROP 1 LASTPIN (-3725 4800) $PN 2
J 0
(-3715 4780);
DISPLAY 0.489362 (-3715 4780);
PAINT MONO (-3715 4780);
FORCEPROP 1 LAST PACK_TYPE C0805
J 0
(-3675 4775);
DISPLAY 0.489362 (-3675 4775);
PAINT SKYBLUE (-3675 4775);
FORCEPROP 1 LAST MATERIAL X6S
J 0
(-3675 4825);
DISPLAY 0.489362 (-3675 4825);
PAINT SKYBLUE (-3675 4825);
FORCEPROP 1 LAST TOLERANCE 20%
J 0
(-3675 4875);
DISPLAY 0.489362 (-3675 4875);
PAINT SKYBLUE (-3675 4875);
FORCEPROP 1 LAST VALUE 22UF
J 0
(-3675 4975);
DISPLAY 0.489362 (-3675 4975);
PAINT SKYBLUE (-3675 4975);
FORCEPROP 1 LAST VOLTAGE 4V
J 0
(-3675 4925);
DISPLAY 0.489362 (-3675 4925);
PAINT SKYBLUE (-3675 4925);
FORCEPROP 2 LAST CDS_LIB pure_quanta
J 0
(-3725 4900);
DISPLAY INVISIBLE (-3725 4900);
FORCEPROP 1 LAST PATH I70
J 0
(-3675 5050);
DISPLAY 0.978723 (-3675 5050);
PAINT WHITE (-3675 5050);
DISPLAY INVISIBLE (-3675 5050);
FORCEPROP 1 LAST PART_NUMBER CH622KMEA03
J 0
(-3675 4725);
DISPLAY 0.489362 (-3675 4725);
PAINT SKYBLUE (-3675 4725);
DISPLAY INVISIBLE (-3675 4725);
FORCEADD VCC_CORE..1
(-3725 5225);
FORCEPROP 3 LASTPIN (-3725 5175) SIG_NAME PVDDIO_P1\g
J 0
(-3715 5185);
DISPLAY 0.659574 (-3715 5185);
PAINT MONO (-3715 5185);
DISPLAY INVISIBLE (-3715 5185);
FORCEPROP 1 LAST HDL_POWER PVDDIO_P1
J 1
(-3725 5275);
DISPLAY 0.489362 (-3725 5275);
PAINT GREEN (-3725 5275);
FORCEPROP 2 LAST CDS_LIB pure_quanta_power
J 0
(-3725 5225);
DISPLAY INVISIBLE (-3725 5225);
FORCEPROP 1 LAST PATH I71
J 0
(-3675 5250);
DISPLAY 0.872340 (-3675 5250);
PAINT AQUA (-3675 5250);
DISPLAY INVISIBLE (-3675 5250);
FORCEADD Q_CAP..1
(-7600 3250);
FORCEPROP 1 LAST LOCATION PC627_4
J 0
(-7550 3400);
DISPLAY 0.489362 (-7550 3400);
PAINT SKYBLUE (-7550 3400);
FORCEPROP 0 LAST $SEC 1
J 0
(-7550 3450);
DISPLAY 0.680851 (-7550 3450);
PAINT MONO (-7550 3450);
DISPLAY INVISIBLE (-7550 3450);
FORCEPROP 0 LAST CDS_SEC 1
J 0
(-7550 3450);
DISPLAY 1.021277 (-7550 3450);
DISPLAY INVISIBLE (-7550 3450);
FORCEPROP 1 LASTPIN (-7600 3350) $PN 1
J 0
(-7590 3330);
DISPLAY 0.489362 (-7590 3330);
PAINT MONO (-7590 3330);
FORCEPROP 1 LASTPIN (-7600 3150) $PN 2
J 0
(-7590 3130);
DISPLAY 0.489362 (-7590 3130);
PAINT MONO (-7590 3130);
FORCEPROP 1 LAST TOLERANCE 20%
J 0
(-7550 3250);
DISPLAY 0.489362 (-7550 3250);
PAINT SKYBLUE (-7550 3250);
FORCEPROP 1 LAST VOLTAGE 16V
J 0
(-7550 3300);
DISPLAY 0.489362 (-7550 3300);
PAINT SKYBLUE (-7550 3300);
FORCEPROP 1 LAST VALUE 22UF
J 0
(-7550 3350);
DISPLAY 0.489362 (-7550 3350);
PAINT SKYBLUE (-7550 3350);
FORCEPROP 1 LAST MATERIAL X6S
J 0
(-7550 3200);
DISPLAY 0.489362 (-7550 3200);
PAINT SKYBLUE (-7550 3200);
FORCEPROP 1 LAST PACK_TYPE C0805
J 0
(-7550 3150);
DISPLAY 0.489362 (-7550 3150);
PAINT SKYBLUE (-7550 3150);
FORCEPROP 2 LAST CDS_LIB pure_quanta
J 0
(-7600 3250);
DISPLAY INVISIBLE (-7600 3250);
FORCEPROP 1 LAST PATH I72
J 0
(-7550 3400);
DISPLAY 0.978723 (-7550 3400);
PAINT WHITE (-7550 3400);
DISPLAY INVISIBLE (-7550 3400);
FORCEPROP 1 LAST PART_NUMBER CH6223MEA01
J 0
(-7550 3100);
DISPLAY 0.489362 (-7550 3100);
PAINT SKYBLUE (-7550 3100);
DISPLAY INVISIBLE (-7550 3100);
FORCEADD ISL99390FRZTR5935..1
(-9350 5100);
FORCEPROP 1 LAST LOCATION PU52
J 0
(-9650 5975);
DISPLAY 0.489362 (-9650 5975);
PAINT SKYBLUE (-9650 5975);
FORCEPROP 2 LAST $SEC 1
J 0
(-9650 6025);
DISPLAY 0.680851 (-9650 6025);
PAINT MONO (-9650 6025);
DISPLAY INVISIBLE (-9650 6025);
FORCEPROP 2 LAST CDS_SEC 1
J 0
(-9600 6100);
DISPLAY 1.021277 (-9600 6100);
DISPLAY INVISIBLE (-9600 6100);
FORCEPROP 2 LASTPIN (-8950 4650) $PN 2
J 0
(-8940 4660);
DISPLAY 0.489362 (-8940 4660);
PAINT MONO (-8940 4660);
FORCEPROP 2 LASTPIN (-8950 5450) $PN 33
J 0
(-8940 5460);
DISPLAY 0.489362 (-8940 5460);
PAINT MONO (-8940 5460);
FORCEPROP 2 LASTPIN (-9800 4850) $PN 31
J 2
(-9810 4860);
DISPLAY 0.489362 (-9810 4860);
PAINT MONO (-9810 4860);
FORCEPROP 2 LASTPIN (-9800 5250) $PN 35
J 2
(-9810 5260);
DISPLAY 0.489362 (-9810 5260);
PAINT MONO (-9810 5260);
FORCEPROP 2 LASTPIN (-8950 4800) $PN 6
J 0
(-8940 4810);
DISPLAY 0.489362 (-8940 4810);
PAINT MONO (-8940 4810);
FORCEPROP 2 LASTPIN (-8950 4750) $PN 41
J 0
(-8940 4760);
DISPLAY 0.489362 (-8940 4760);
PAINT MONO (-8940 4760);
FORCEPROP 2 LASTPIN (-9800 5100) $PN 38
J 2
(-9810 5110);
DISPLAY 0.489362 (-9810 5110);
PAINT MONO (-9810 5110);
FORCEPROP 2 LASTPIN (-9800 4800) $PN 37
J 2
(-9810 4810);
DISPLAY 0.489362 (-9810 4810);
PAINT MONO (-9810 4810);
FORCEPROP 2 LASTPIN (-8950 4600) $PN 5
J 0
(-8940 4610);
DISPLAY 0.489362 (-8940 4610);
PAINT MONO (-8940 4610);
FORCEPROP 2 LASTPIN (-8950 4550) $PN 7_9-20_24
J 0
(-8940 4560);
DISPLAY 0.489362 (-8940 4560);
PAINT MONO (-8940 4560);
FORCEPROP 2 LASTPIN (-8950 4500) $PN 40
J 0
(-8940 4510);
DISPLAY 0.489362 (-8940 4510);
PAINT MONO (-8940 4510);
FORCEPROP 2 LASTPIN (-8950 5200) $PN 32
J 0
(-8940 5210);
DISPLAY 0.489362 (-8940 5210);
PAINT MONO (-8940 5210);
FORCEPROP 2 LASTPIN (-9800 5750) $PN 4
J 2
(-9810 5760);
DISPLAY 0.489362 (-9810 5760);
PAINT MONO (-9810 5760);
FORCEPROP 2 LASTPIN (-9800 4500) $PN 34
J 2
(-9810 4510);
DISPLAY 0.489362 (-9810 4510);
PAINT MONO (-9810 4510);
FORCEPROP 2 LASTPIN (-9800 5000) $PN 39
J 2
(-9810 5010);
DISPLAY 0.489362 (-9810 5010);
PAINT MONO (-9810 5010);
FORCEPROP 2 LASTPIN (-8950 5100) $PN 10_19
J 0
(-8940 5110);
DISPLAY 0.489362 (-8940 5110);
PAINT MONO (-8940 5110);
FORCEPROP 2 LASTPIN (-9800 4600) $PN 36
J 2
(-9810 4610);
DISPLAY 0.489362 (-9810 4610);
PAINT MONO (-9810 4610);
FORCEPROP 2 LASTPIN (-9800 5450) $PN 3
J 2
(-9810 5460);
DISPLAY 0.489362 (-9810 5460);
PAINT MONO (-9810 5460);
FORCEPROP 2 LASTPIN (-8950 5750) $PN 25_29
J 0
(-8940 5760);
DISPLAY 0.489362 (-8940 5760);
PAINT MONO (-8940 5760);
FORCEPROP 2 LASTPIN (-8950 5700) $PN 30
J 0
(-8940 5710);
DISPLAY 0.489362 (-8940 5710);
PAINT MONO (-8940 5710);
FORCEPROP 2 LASTPIN (-8950 4850) $PN 1
J 0
(-8940 4860);
DISPLAY 0.489362 (-8940 4860);
PAINT MONO (-8940 4860);
FORCEPROP 2 LAST VALUE ISL99390FRZ-TR5935
J 0
(-9650 6075);
DISPLAY 0.489362 (-9650 6075);
PAINT SKYBLUE (-9650 6075);
FORCEPROP 1 LAST MATERIAL IC
J 0
(-9650 5825);
DISPLAY 0.489362 (-9650 5825);
PAINT SKYBLUE (-9650 5825);
FORCEPROP 2 LAST PART_TYPE SMLF
J 0
(-9650 6125);
DISPLAY 0.638298 (-9650 6125);
FORCEPROP 1 LAST NEEDS_NO_SIZE TRUE
J 0
(-9350 5100);
DISPLAY 0.723404 (-9350 5100);
PAINT GREEN (-9350 5100);
DISPLAY INVISIBLE (-9350 5100);
FORCEPROP 1 LAST CDS_LMAN_SYM_OUTLINE -300,700,250,-650
J 0
(-9350 5100);
DISPLAY 0.468085 (-9350 5100);
PAINT GREEN (-9350 5100);
DISPLAY INVISIBLE (-9350 5100);
FORCEPROP 2 LAST CDS_LIB pure_quanta
J 0
(-9350 5100);
DISPLAY INVISIBLE (-9350 5100);
FORCEPROP 1 LAST PATH I73
J 0
(-9350 5100);
DISPLAY 0.723404 (-9350 5100);
PAINT GREEN (-9350 5100);
DISPLAY INVISIBLE (-9350 5100);
FORCEPROP 1 LAST PART_NUMBER AL099390004
J 0
(-9650 5900);
DISPLAY 0.489362 (-9650 5900);
PAINT SKYBLUE (-9650 5900);
DISPLAY INVISIBLE (-9650 5900);
FORCEADD OFFPAGE..5
(-10900 2300);
FORCEPROP 2 LAST $XR0 217 
J 0
(-11155 2300);
DISPLAY 0.638298 (-11155 2300);
PAINT MONO (-11155 2300);
FORCEPROP 2 LAST CDS_LIB standard
J 0
(-10900 2300);
DISPLAY INVISIBLE (-10900 2300);
FORCEPROP 1 LAST OFFPAGE TRUE
J 0
(-10575 2175);
DISPLAY 0.872340 (-10575 2175);
PAINT GREEN (-10575 2175);
DISPLAY INVISIBLE (-10575 2175);
FORCEPROP 1 LAST COMMENT_BODY TRUE
J 0
(-10800 2225);
DISPLAY 0.872340 (-10800 2225);
PAINT GREEN (-10800 2225);
DISPLAY INVISIBLE (-10800 2225);
FORCEPROP 2 LAST PATH I8
J 0
(-11175 2350);
DISPLAY 0.680851 (-11175 2350);
DISPLAY INVISIBLE (-11175 2350);
FORCEADD UNIVERSAL_GND..1
(-11050 2500);
FORCEPROP 3 LASTPIN (-11050 2550) SIG_NAME GND\g
J 0
(-11040 2560);
DISPLAY 0.659574 (-11040 2560);
PAINT MONO (-11040 2560);
DISPLAY INVISIBLE (-11040 2560);
FORCEPROP 2 LAST CDS_LIB pure_quanta_power
J 0
(-11050 2500);
DISPLAY INVISIBLE (-11050 2500);
FORCEPROP 1 LAST HDL_POWER GND
J 1
(-11025 2425);
DISPLAY 0.872340 (-11025 2425);
PAINT GREEN (-11025 2425);
DISPLAY INVISIBLE (-11025 2425);
FORCEPROP 1 LAST PATH I9
J 0
(-10975 2500);
DISPLAY 0.872340 (-10975 2500);
PAINT AQUA (-10975 2500);
DISPLAY INVISIBLE (-10975 2500);
FORCEADD DNS..1
(-7950 4900);
PAINT RED (-7950 4900);
FORCEPROP 2 LAST CDS_LIB mstr_misc
J 0
(-7950 4900);
DISPLAY INVISIBLE (-7950 4900);
FORCEPROP 1 LAST COMMENT_BODY TRUE
R 1
J 0
(-7875 4675);
DISPLAY 0.872340 (-7875 4675);
PAINT GREEN (-7875 4675);
DISPLAY INVISIBLE (-7875 4675);
FORCEADD DNS..1
(-7950 4400);
PAINT RED (-7950 4400);
FORCEPROP 2 LAST CDS_LIB mstr_misc
J 0
(-7950 4400);
DISPLAY INVISIBLE (-7950 4400);
FORCEPROP 1 LAST COMMENT_BODY TRUE
R 1
J 0
(-7875 4175);
DISPLAY 0.872340 (-7875 4175);
PAINT GREEN (-7875 4175);
DISPLAY INVISIBLE (-7875 4175);
FORCEADD DNS..1
(-11350 4625);
PAINT RED (-11350 4625);
FORCEPROP 2 LAST CDS_LIB mstr_misc
J 0
(-11350 4625);
PAINT MONO (-11350 4625);
DISPLAY INVISIBLE (-11350 4625);
FORCEPROP 1 LAST COMMENT_BODY TRUE
R 1
J 0
(-11275 4400);
DISPLAY 0.872340 (-11275 4400);
PAINT GREEN (-11275 4400);
DISPLAY INVISIBLE (-11275 4400);
FORCEADD DNS..1
(-8050 2100);
PAINT RED (-8050 2100);
FORCEPROP 2 LAST CDS_LIB mstr_misc
J 0
(-8050 2100);
DISPLAY INVISIBLE (-8050 2100);
FORCEPROP 1 LAST COMMENT_BODY TRUE
R 1
J 0
(-7975 1875);
DISPLAY 0.872340 (-7975 1875);
PAINT GREEN (-7975 1875);
DISPLAY INVISIBLE (-7975 1875);
FORCEADD DNS..1
(-8050 1600);
PAINT RED (-8050 1600);
FORCEPROP 2 LAST CDS_LIB mstr_misc
J 0
(-8050 1600);
DISPLAY INVISIBLE (-8050 1600);
FORCEPROP 1 LAST COMMENT_BODY TRUE
R 1
J 0
(-7975 1375);
DISPLAY 0.872340 (-7975 1375);
PAINT GREEN (-7975 1375);
DISPLAY INVISIBLE (-7975 1375);
FORCEADD DNS..1
(-11375 1775);
PAINT RED (-11375 1775);
FORCEPROP 2 LAST CDS_LIB mstr_misc
J 0
(-11375 1775);
PAINT MONO (-11375 1775);
DISPLAY INVISIBLE (-11375 1775);
FORCEPROP 1 LAST COMMENT_BODY TRUE
R 1
J 0
(-11300 1550);
DISPLAY 0.872340 (-11300 1550);
PAINT GREEN (-11300 1550);
DISPLAY INVISIBLE (-11300 1550);
FORCEADD QUANTA_TITLE_BLOCK_C..1
(-3200 375);
FORCEPROP 0 LAST CDS_CON_LAST_MODIFIED Thu Sep 14 16:12:22 2023
J 0
(-5085 390);
DISPLAY INVISIBLE (-5085 390);
FORCEPROP 1 LAST CUSTOM_TXT_CDS <CON_LAST_MODIFIED>
J 0
(-5085 390);
DISPLAY 0.978723 (-5085 390);
FORCEPROP 2 LAST CUSTOM_TXT_CDS <XR_PAGE_TITLE>
J 0
(-11090 5625);
DISPLAY 0.638298 (-11090 5625);
PAINT PINK (-11090 5625);
DISPLAY INVISIBLE (-11090 5625);
FORCEPROP 1 LAST CUSTOM_TXT_CDS <NAME_2>
J 0
(-6375 425);
FORCEPROP 1 LAST CUSTOM_TXT_CDS <NAME_1>
J 0
(-6375 550);
FORCEPROP 1 LAST CUSTOM_TXT_CDS <Q_NUMBER>
J 0
(-4603 478);
DISPLAY 1.212766 (-4603 478);
FORCEPROP 1 LAST CUSTOM_TXT_CDS <Q_PROJ>
J 0
(-5582 477);
DISPLAY 1.212766 (-5582 477);
FORCEPROP 1 LAST CUSTOM_TXT_CDS <Q_REV>
J 0
(-3384 478);
DISPLAY 1.212766 (-3384 478);
FORCEPROP 1 LAST CUSTOM_TXT_CDS <CON_PAGE_NUM> OF <CON_TOTAL_PAGES>
J 0
(-3646 393);
DISPLAY 0.978723 (-3646 393);
FORCEPROP 1 LAST Q_TITLE PVDDIO_P1 VR PHASE 3&4
J 0
(-12500 425);
DISPLAY 2.446809 (-12500 425);
PAINT GREEN (-12500 425);
FORCEPROP 2 LAST CDS_LIB pure_quanta
J 0
(-3200 375);
DISPLAY INVISIBLE (-3200 375);
FORCEPROP 1 LAST CDS_LMAN_SYM_OUTLINE -9475,6775,100,-125
J 0
(-3200 375);
DISPLAY 0.468085 (-3200 375);
PAINT GREEN (-3200 375);
DISPLAY INVISIBLE (-3200 375);
FORCEPROP 2 LAST PAGE_BORDER TRUE
J 0
(-11090 5625);
DISPLAY 0.638298 (-11090 5625);
PAINT PINK (-11090 5625);
DISPLAY INVISIBLE (-11090 5625);
FORCEPROP 2 LAST CDS_XR_PAGE_TITLE CR-223 : @T6G_MB_LIB.T6G(SCH_1):PAGE223
J 0
(-11090 5625);
DISPLAY 0.638298 (-11090 5625);
PAINT PINK (-11090 5625);
DISPLAY INVISIBLE (-11090 5625);
FORCEPROP 1 LAST Q_DEPT BU9
J 1
(-6963 424);
DISPLAY 1.957447 (-6963 424);
PAINT GREEN (-6963 424);
DISPLAY INVISIBLE (-6963 424);
FORCEPROP 1 LAST COMMENT_BODY TRUE
J 0
(-3188 362);
DISPLAY 0.978723 (-3188 362);
PAINT GREEN (-3188 362);
DISPLAY INVISIBLE (-3188 362);
WIRE 16 -1 (-11925 1775)(-11925 1825);
WIRE 16 -1 (-10700 3175)(-10700 3050);
WIRE 16 -1 (-11900 4575)(-11900 4625);
WIRE 16 -1 (-11350 4550)(-11350 4475);
WIRE 16 -1 (-11025 5300)(-11025 5250);
WIRE 16 -1 (-11375 1700)(-11375 1625);
WIRE 16 -1 (-10675 5875)(-10675 5750);
WIRE 16 -1 (-8025 1500)(-8025 1425);
WIRE 16 -1 (-7400 2050)(-7600 2050);
WIRE 16 -1 (-7600 2050)(-7600 2000);
WIRE 16 -1 (-7925 4300)(-7925 4225);
WIRE 16 -1 (-11050 2600)(-11050 2550);
WIRE 16 -1 (-6725 3350)(-6725 3500);
WIRE 16 -1 (-6725 3575)(-6725 3500);
WIRE 16 -1 (-6725 3500)(-7200 3500);
WIRE 16 -1 (-7200 3350)(-7200 3500);
WIRE 16 -1 (-7600 3500)(-7200 3500);
WIRE 16 -1 (-7600 3500)(-7600 3350);
WIRE 16 -1 (-8000 3500)(-7600 3500);
WIRE 16 -1 (-8000 3350)(-8000 3500);
WIRE 16 -1 (-8475 3500)(-8000 3500);
WIRE 16 -1 (-8475 3375)(-8475 3500);
WIRE 16 -1 (-8775 3500)(-8475 3500);
WIRE 16 -1 (-8775 3500)(-8775 2950);
WIRE 16 -1 (-8950 2950)(-8775 2950);
WIRE 16 -1 (-8775 2950)(-8775 2900);
WIRE 16 -1 (-8775 2900)(-8950 2900);
WIRE 16 -1 (-6725 3150)(-6725 3000);
WIRE 16 -1 (-6725 2925)(-6725 3000);
WIRE 16 -1 (-6725 3000)(-7200 3000);
WIRE 16 -1 (-7200 3150)(-7200 3000);
WIRE 16 -1 (-7600 3000)(-7200 3000);
WIRE 16 -1 (-7600 3150)(-7600 3000);
WIRE 16 -1 (-7600 3000)(-8000 3000);
WIRE 16 -1 (-8000 3150)(-8000 3000);
WIRE 16 -1 (-8475 3000)(-8000 3000);
WIRE 16 -1 (-8475 3175)(-8475 3000);
WIRE 16 -1 (-8950 4850)(-8225 4850);
FORCEPROP 2 LAST SIG_NAME PVDDIO_P1_VOS3
J 0
(-8860 4875);
DISPLAY 0.489362 (-8860 4875);
FORCEPROP 2 LASTPROP $XRERR UNIQUE?
J 0
(-9100 4875);
DISPLAY 0.638298 (-9100 4875);
PAINT MONO (-9100 4875);
DISPLAY INVISIBLE (-9100 4875);
WIRE 16 -1 (-8225 4850)(-8225 4075);
WIRE 16 -1 (-7050 4075)(-8225 4075);
WIRE 16 -1 (-7925 5000)(-7925 5100);
WIRE 16 -1 (-7925 5100)(-6425 5100);
WIRE 16 -1 (-8950 5100)(-7925 5100);
FORCEPROP 2 LAST SIG_NAME SW_PVDDIO_P1_SW3
J 0
(-8760 5110);
DISPLAY 0.489362 (-8760 5110);
FORCEPROP 2 LASTPROP $XRERR UNIQUE?
J 0
(-9000 5110);
DISPLAY 0.638298 (-9000 5110);
PAINT MONO (-9000 5110);
DISPLAY INVISIBLE (-9000 5110);
WIRE 16 -1 (-6950 5200)(-6950 5225);
WIRE 16 -1 (-8950 5200)(-6950 5200);
FORCEPROP 2 LAST SIG_NAME SW_PVDDIO_P1_BOOTR3
J 0
(-8760 5210);
DISPLAY 0.489362 (-8760 5210);
FORCEPROP 2 LASTPROP $XRERR UNIQUE?
J 0
(-9000 5210);
DISPLAY 0.638298 (-9000 5210);
PAINT MONO (-9000 5210);
DISPLAY INVISIBLE (-9000 5210);
WIRE 16 -1 (-8950 5450)(-8075 5450);
FORCEPROP 2 LAST SIG_NAME SW_PVDDIO_P1_BOOT3
J 0
(-8760 5485);
DISPLAY 0.489362 (-8760 5485);
FORCEPROP 2 LASTPROP $XRERR UNIQUE?
J 0
(-9000 5485);
DISPLAY 0.638298 (-9000 5485);
PAINT MONO (-9000 5485);
DISPLAY INVISIBLE (-9000 5485);
WIRE 16 -1 (-6950 5450)(-6950 5425);
WIRE 16 -1 (-7875 5450)(-6950 5450);
FORCEPROP 2 LAST SIG_NAME SW_PVDDIO_P1_BOOT3_R
J 0
(-7385 5460);
DISPLAY 0.489362 (-7385 5460);
FORCEPROP 2 LASTPROP $XRERR UNIQUE?
J 0
(-7625 5460);
DISPLAY 0.638298 (-7625 5460);
PAINT MONO (-7625 5460);
DISPLAY INVISIBLE (-7625 5460);
WIRE 16 -1 (-8950 2650)(-8150 2650);
FORCEPROP 2 LAST SIG_NAME SW_PVDDIO_P1_BOOT4
J 0
(-8735 2660);
DISPLAY 0.489362 (-8735 2660);
FORCEPROP 2 LASTPROP $XRERR UNIQUE?
J 0
(-8975 2660);
DISPLAY 0.638298 (-8975 2660);
PAINT MONO (-8975 2660);
DISPLAY INVISIBLE (-8975 2660);
WIRE 16 -1 (-7025 2650)(-7025 2625);
WIRE 16 -1 (-7950 2650)(-7025 2650);
FORCEPROP 2 LAST SIG_NAME SW_PVDDIO_P1_BOOT4_R
J 0
(-7660 2660);
DISPLAY 0.489362 (-7660 2660);
FORCEPROP 2 LASTPROP $XRERR UNIQUE?
J 0
(-7900 2660);
DISPLAY 0.638298 (-7900 2660);
PAINT MONO (-7900 2660);
DISPLAY INVISIBLE (-7900 2660);
WIRE 16 -1 (-8500 5950)(-8500 5800);
WIRE 16 -1 (-8500 5800)(-8075 5800);
WIRE 16 -1 (-7675 5800)(-8075 5800);
WIRE 16 -1 (-8075 5950)(-8075 5800);
WIRE 16 -1 (-7675 5800)(-7275 5800);
WIRE 16 -1 (-7675 5950)(-7675 5800);
WIRE 16 -1 (-6850 5800)(-7275 5800);
WIRE 16 -1 (-7275 5950)(-7275 5800);
WIRE 16 -1 (-6850 5975)(-6850 5800);
WIRE 16 -1 (-6850 5725)(-6850 5800);
WIRE 16 -1 (-11050 3350)(-11050 3475);
WIRE 16 -1 (-10700 3475)(-11050 3475);
WIRE 16 -1 (-11050 3600)(-11050 3475);
WIRE 16 -1 (-10700 3475)(-9950 3475);
WIRE 16 -1 (-10700 3375)(-10700 3475);
WIRE 16 -1 (-9950 2950)(-9950 3475);
WIRE 16 -1 (-9950 2950)(-9800 2950);
WIRE 16 -1 (-8950 1750)(-8700 1750);
WIRE 16 -1 (-8700 1800)(-8700 1750);
WIRE 16 -1 (-8700 1750)(-8700 1700);
WIRE 16 -1 (-8950 1700)(-8700 1700);
WIRE 16 -1 (-8700 1700)(-8700 1625);
WIRE 16 -1 (-8700 1800)(-8700 1850);
WIRE 16 -1 (-8950 1800)(-8700 1800);
WIRE 16 -1 (-8700 1850)(-8950 1850);
WIRE 16 -1 (-11025 6050)(-11025 6175);
WIRE 16 -1 (-10675 6175)(-11025 6175);
WIRE 16 -1 (-11025 6300)(-11025 6175);
WIRE 16 -1 (-10350 6175)(-10675 6175);
WIRE 16 -1 (-10675 6075)(-10675 6175);
WIRE 16 -1 (-10350 5750)(-10350 6175);
WIRE 16 -1 (-10350 5750)(-9800 5750);
WIRE 16 -1 (-8950 4550)(-8700 4550);
WIRE 16 -1 (-8700 4600)(-8700 4550);
WIRE 16 -1 (-8700 4550)(-8700 4500);
WIRE 16 -1 (-8950 4500)(-8700 4500);
WIRE 16 -1 (-8700 4500)(-8700 4425);
WIRE 16 -1 (-8700 4600)(-8700 4650);
WIRE 16 -1 (-8950 4600)(-8700 4600);
WIRE 16 -1 (-8700 4650)(-8950 4650);
WIRE 16 -1 (-4050 2000)(-4050 1875);
WIRE 16 -1 (-4050 1800)(-4050 1875);
WIRE 16 -1 (-4050 1875)(-4475 1875);
WIRE 16 -1 (-4475 1875)(-4475 2000);
WIRE 16 -1 (-4050 2200)(-4050 2300);
WIRE 16 -1 (-4050 2375)(-4050 2300);
WIRE 16 -1 (-4475 2300)(-4050 2300);
WIRE 16 -1 (-4475 2200)(-4475 2300);
WIRE 16 -1 (-4475 2300)(-4875 2300);
WIRE 16 -1 (-4875 2300)(-5875 2300);
WIRE 16 -1 (-4875 1275)(-4875 2300);
WIRE 16 -1 (-4875 1275)(-6650 1275);
WIRE 16 -1 (-6850 6300)(-6850 6175);
WIRE 16 -1 (-6850 6375)(-6850 6300);
WIRE 16 -1 (-6850 6300)(-7275 6300);
WIRE 16 -1 (-7275 6150)(-7275 6300);
WIRE 16 -1 (-7675 6300)(-7275 6300);
WIRE 16 -1 (-7675 6300)(-7675 6150);
WIRE 16 -1 (-8075 6300)(-7675 6300);
WIRE 16 -1 (-8075 6150)(-8075 6300);
WIRE 16 -1 (-8500 6300)(-8075 6300);
WIRE 16 -1 (-8500 6150)(-8500 6300);
WIRE 16 -1 (-8775 6300)(-8500 6300);
WIRE 16 -1 (-8775 6300)(-8775 5750);
WIRE 16 -1 (-8950 5750)(-8775 5750);
WIRE 16 -1 (-8775 5750)(-8775 5700);
WIRE 16 -1 (-8775 5700)(-8950 5700);
WIRE 16 -1 (-3725 4800)(-3725 4675);
WIRE 16 -1 (-3725 4625)(-3725 4675);
WIRE 16 -1 (-3725 4675)(-4150 4675);
WIRE 16 -1 (-4150 4675)(-4150 4800);
WIRE 16 -1 (-4525 5100)(-4150 5100);
WIRE 16 -1 (-4525 5100)(-5625 5100);
WIRE 16 -1 (-4525 5100)(-4525 4075);
WIRE 16 -1 (-4150 5100)(-3725 5100);
WIRE 16 -1 (-4150 5100)(-4150 5000);
WIRE 16 -1 (-3725 5175)(-3725 5100);
WIRE 16 -1 (-3725 5000)(-3725 5100);
WIRE 16 -1 (-4525 4075)(-6850 4075);
WIRE 16 -1 (-11375 2000)(-9800 2000);
FORCEPROP 2 LAST SIG_NAME PVDDIO_P1_LSET4
J 0
(-10785 2010);
DISPLAY 0.489362 (-10785 2010);
FORCEPROP 2 LASTPROP $XRERR UNIQUE?
J 0
(-11025 2010);
DISPLAY 0.638298 (-11025 2010);
PAINT MONO (-11025 2010);
DISPLAY INVISIBLE (-11025 2010);
WIRE 16 -1 (-11375 2000)(-11375 1900);
WIRE 16 -1 (-9800 2300)(-10850 2300);
FORCEPROP 2 LAST SIG_NAME PVDDIO_P1_IMON4
J 0
(-10785 2310);
DISPLAY 0.489362 (-10785 2310);
WIRE 16 -1 (-9800 1800)(-10850 1800);
FORCEPROP 2 LAST SIG_NAME PVDDIO_P1_TEMP1
J 0
(-10785 1810);
DISPLAY 0.489362 (-10785 1810);
WIRE 16 -1 (-9800 1700)(-10850 1700);
FORCEPROP 2 LAST SIG_NAME PVDDIO_P1_PWM4
J 0
(-10785 1710);
DISPLAY 0.489362 (-10785 1710);
WIRE 16 -1 (-9950 2200)(-9950 2125);
FORCEPROP 0 LAST CDS_PHYS_NET_NAME PVDDCR_CPU1_P1_VCCS
J 0
(-9950 2150);
PAINT MONO (-9950 2150);
DISPLAY INVISIBLE (-9950 2150);
WIRE 16 -1 (-9950 2200)(-9800 2200);
WIRE 16 -1 (-10850 2200)(-9950 2200);
FORCEPROP 2 LAST SIG_NAME PVDDCR_CPU1_P1_VCCS
J 0
(-10785 2210);
DISPLAY 0.489362 (-10785 2210);
WIRE 16 -1 (-9950 2125)(-11925 2125);
WIRE 16 -1 (-11925 2125)(-11925 2025);
WIRE 16 -1 (-10225 2050)(-9800 2050);
FORCEPROP 2 LAST SIG_NAME NC_PVDDIO_P1_DNC4
J 0
(-10295 2060);
DISPLAY 0.489362 (-10295 2060);
FORCEPROP 2 LASTPROP $XRERR UNIQUE?
J 0
(-10465 2050);
DISPLAY 0.638298 (-10465 2050);
PAINT MONO (-10465 2050);
DISPLAY INVISIBLE (-10465 2050);
WIRE 16 -1 (-8950 2000)(-8450 2000);
FORCEPROP 2 LAST SIG_NAME NC_PVDDIO_P1_GL1_4
J 0
(-8835 2010);
DISPLAY 0.489362 (-8835 2010);
FORCEPROP 2 LASTPROP $XRERR UNIQUE?
J 0
(-8420 2000);
DISPLAY 0.638298 (-8420 2000);
PAINT MONO (-8420 2000);
DISPLAY INVISIBLE (-8420 2000);
WIRE 16 -1 (-8950 1950)(-8450 1950);
FORCEPROP 2 LAST SIG_NAME NC_PVDDIO_P1_GL2_4
J 0
(-8835 1960);
DISPLAY 0.489362 (-8835 1960);
FORCEPROP 2 LASTPROP $XRERR UNIQUE?
J 0
(-8420 1950);
DISPLAY 0.638298 (-8420 1950);
PAINT MONO (-8420 1950);
DISPLAY INVISIBLE (-8420 1950);
WIRE 16 -1 (-8950 2050)(-8250 2050);
FORCEPROP 2 LAST SIG_NAME PVDDIO_P1_VOS4
J 0
(-8835 2075);
DISPLAY 0.489362 (-8835 2075);
FORCEPROP 2 LASTPROP $XRERR UNIQUE?
J 0
(-9075 2075);
DISPLAY 0.638298 (-9075 2075);
PAINT MONO (-9075 2075);
DISPLAY INVISIBLE (-9075 2075);
WIRE 16 -1 (-8250 2050)(-8250 1275);
WIRE 16 -1 (-6850 1275)(-8250 1275);
WIRE 16 -1 (-9800 2450)(-9950 2450);
WIRE 16 -1 (-9950 2650)(-9950 2450);
WIRE 16 -1 (-9800 2650)(-9950 2650);
WIRE 16 -1 (-9950 2650)(-10475 2650);
FORCEPROP 0 LAST CDS_PHYS_NET_NAME PVDDIO_P1_VCC4
J 0
(-10360 2690);
PAINT MONO (-10360 2690);
DISPLAY INVISIBLE (-10360 2690);
FORCEPROP 2 LAST SIG_NAME PVDDIO_P1_VCC4
J 0
(-10385 2660);
DISPLAY 0.489362 (-10385 2660);
FORCEPROP 2 LASTPROP $XRERR UNIQUE?
J 0
(-10625 2660);
DISPLAY 0.638298 (-10625 2660);
PAINT MONO (-10625 2660);
DISPLAY INVISIBLE (-10625 2660);
WIRE 16 -1 (-10475 2875)(-10475 2650);
WIRE 16 -1 (-11050 2875)(-10475 2875);
WIRE 16 -1 (-11050 3150)(-11050 2875);
WIRE 16 -1 (-11050 2875)(-11050 2800);
WIRE 16 -1 (-11350 4800)(-9800 4800);
FORCEPROP 0 LAST CDS_PHYS_NET_NAME PVDDIO_P1_LSET3
J 0
(-10760 4840);
PAINT MONO (-10760 4840);
DISPLAY INVISIBLE (-10760 4840);
FORCEPROP 2 LAST SIG_NAME PVDDIO_P1_LSET3
J 0
(-10760 4810);
DISPLAY 0.489362 (-10760 4810);
FORCEPROP 2 LASTPROP $XRERR UNIQUE?
J 0
(-11000 4810);
DISPLAY 0.638298 (-11000 4810);
PAINT MONO (-11000 4810);
DISPLAY INVISIBLE (-11000 4810);
WIRE 16 -1 (-11350 4800)(-11350 4750);
WIRE 16 -1 (-9800 5100)(-10825 5100);
FORCEPROP 2 LAST SIG_NAME PVDDIO_P1_IMON3
J 0
(-10760 5110);
DISPLAY 0.489362 (-10760 5110);
WIRE 16 -1 (-9800 4600)(-10825 4600);
FORCEPROP 2 LAST SIG_NAME PVDDIO_P1_TEMP1
J 0
(-10760 4610);
DISPLAY 0.489362 (-10760 4610);
WIRE 16 -1 (-9800 4500)(-10825 4500);
FORCEPROP 2 LAST SIG_NAME PVDDIO_P1_PWM3
J 0
(-10760 4510);
DISPLAY 0.489362 (-10760 4510);
WIRE 16 -1 (-9950 5000)(-9950 4925);
FORCEPROP 0 LAST CDS_PHYS_NET_NAME PVDDCR_CPU1_P1_VCCS
J 0
(-9950 4950);
PAINT MONO (-9950 4950);
DISPLAY INVISIBLE (-9950 4950);
WIRE 16 -1 (-9950 5000)(-9800 5000);
WIRE 16 -1 (-10825 5000)(-9950 5000);
FORCEPROP 2 LAST SIG_NAME PVDDCR_CPU1_P1_VCCS
J 0
(-10760 5010);
DISPLAY 0.489362 (-10760 5010);
WIRE 16 -1 (-9950 4925)(-11900 4925);
WIRE 16 -1 (-11900 4925)(-11900 4825);
WIRE 16 -1 (-10225 4850)(-9800 4850);
FORCEPROP 2 LAST SIG_NAME NC_PVDDIO_P1_DNC3
J 0
(-10320 4860);
DISPLAY 0.489362 (-10320 4860);
FORCEPROP 2 LASTPROP $XRERR UNIQUE?
J 0
(-10465 4850);
DISPLAY 0.638298 (-10465 4850);
PAINT MONO (-10465 4850);
DISPLAY INVISIBLE (-10465 4850);
WIRE 16 -1 (-9800 5250)(-9950 5250);
WIRE 16 -1 (-9950 5450)(-9950 5250);
WIRE 16 -1 (-9800 5450)(-9950 5450);
WIRE 16 -1 (-9950 5450)(-10375 5450);
FORCEPROP 0 LAST CDS_PHYS_NET_NAME PVDDIO_P1_VCC3
J 0
(-10310 5490);
PAINT MONO (-10310 5490);
DISPLAY INVISIBLE (-10310 5490);
FORCEPROP 2 LAST SIG_NAME PVDDIO_P1_VCC3
J 0
(-10335 5460);
DISPLAY 0.489362 (-10335 5460);
FORCEPROP 2 LASTPROP $XRERR UNIQUE?
J 0
(-10575 5460);
DISPLAY 0.638298 (-10575 5460);
PAINT MONO (-10575 5460);
DISPLAY INVISIBLE (-10575 5460);
WIRE 16 -1 (-10375 5450)(-10375 5575);
WIRE 16 -1 (-11025 5575)(-10375 5575);
WIRE 16 -1 (-11025 5850)(-11025 5575);
WIRE 16 -1 (-11025 5575)(-11025 5500);
WIRE 16 -1 (-8500 4750)(-8950 4750);
FORCEPROP 2 LAST SIG_NAME NC_PVDDIO_P1_GL2_3
J 0
(-8860 4760);
DISPLAY 0.489362 (-8860 4760);
FORCEPROP 2 LASTPROP $XRERR UNIQUE?
J 0
(-8470 4750);
DISPLAY 0.638298 (-8470 4750);
PAINT MONO (-8470 4750);
DISPLAY INVISIBLE (-8470 4750);
WIRE 16 -1 (-8500 4800)(-8950 4800);
FORCEPROP 2 LAST SIG_NAME NC_PVDDIO_P1_GL1_3
J 0
(-8860 4810);
DISPLAY 0.489362 (-8860 4810);
FORCEPROP 2 LASTPROP $XRERR UNIQUE?
J 0
(-8470 4800);
DISPLAY 0.638298 (-8470 4800);
PAINT MONO (-8470 4800);
DISPLAY INVISIBLE (-8470 4800);
WIRE 16 -1 (-8025 2000)(-8025 1700);
FORCEPROP 2 LAST SIG_NAME SW_PVDDIO_P1_SW4_RC
J 0
(-7985 1810);
DISPLAY 0.489362 (-7985 1810);
FORCEPROP 2 LASTPROP $XRERR UNIQUE?
J 0
(-8225 1810);
DISPLAY 0.638298 (-8225 1810);
PAINT MONO (-8225 1810);
DISPLAY INVISIBLE (-8225 1810);
WIRE 16 -1 (-7200 2050)(-6675 2050);
FORCEPROP 2 LAST SIG_NAME IND_PVDDIO_P1_CPL0
J 0
(-7135 2075);
DISPLAY 0.489362 (-7135 2075);
FORCEPROP 2 LASTPROP $XRERR UNIQUE?
J 0
(-7375 2075);
DISPLAY 0.638298 (-7375 2075);
PAINT MONO (-7375 2075);
DISPLAY INVISIBLE (-7375 2075);
WIRE 16 -1 (-5875 2050)(-5375 2050);
FORCEPROP 2 LAST SIG_NAME IND_PVDDIO_P1_CPL4
J 0
(-5835 2060);
DISPLAY 0.489362 (-5835 2060);
WIRE 16 -1 (-7925 4800)(-7925 4500);
FORCEPROP 2 LAST SIG_NAME SW_PVDDIO_P1_SW3_RC
J 0
(-7885 4635);
DISPLAY 0.489362 (-7885 4635);
FORCEPROP 2 LASTPROP $XRERR UNIQUE?
J 0
(-8125 4635);
DISPLAY 0.638298 (-8125 4635);
PAINT MONO (-8125 4635);
DISPLAY INVISIBLE (-8125 4635);
WIRE 16 -1 (-6425 4850)(-7000 4850);
FORCEPROP 2 LAST SIG_NAME IND_PVDDIO_P1_CPL4
J 0
(-6885 4860);
DISPLAY 0.489362 (-6885 4860);
WIRE 16 -1 (-5625 4850)(-5000 4850);
FORCEPROP 2 LAST SIG_NAME IND_PVDDIO_P1_CPL3
J 0
(-5535 4860);
DISPLAY 0.489362 (-5535 4860);
WIRE 16 -1 (-8950 2300)(-8025 2300);
FORCEPROP 2 LAST SIG_NAME SW_PVDDIO_P1_SW4
J 0
(-8760 2310);
DISPLAY 0.489362 (-8760 2310);
FORCEPROP 2 LASTPROP $XRERR UNIQUE?
J 0
(-9000 2310);
DISPLAY 0.638298 (-9000 2310);
PAINT MONO (-9000 2310);
DISPLAY INVISIBLE (-9000 2310);
WIRE 16 -1 (-8025 2300)(-6675 2300);
WIRE 16 -1 (-8025 2200)(-8025 2300);
WIRE 16 -1 (-8950 2400)(-7025 2400);
FORCEPROP 2 LAST SIG_NAME SW_PVDDIO_P1_BOOTR4
J 0
(-8760 2410);
DISPLAY 0.489362 (-8760 2410);
FORCEPROP 2 LASTPROP $XRERR UNIQUE?
J 0
(-9000 2410);
DISPLAY 0.638298 (-9000 2410);
PAINT MONO (-9000 2410);
DISPLAY INVISIBLE (-9000 2410);
WIRE 16 -1 (-7025 2400)(-7025 2425);
DOT 1 (-8075 5800);
DOT 1 (-11050 2875);
DOT 1 (-11050 3475);
DOT 1 (-10700 3475);
DOT 1 (-8700 1750);
DOT 1 (-8700 1700);
DOT 1 (-8700 1800);
DOT 1 (-9950 2200);
DOT 1 (-9950 2650);
DOT 1 (-8775 2950);
DOT 1 (-8475 3500);
DOT 1 (-11025 5575);
DOT 1 (-11025 6175);
DOT 1 (-10675 6175);
DOT 1 (-9950 5000);
DOT 1 (-9950 5450);
DOT 1 (-8700 4500);
DOT 1 (-8700 4550);
DOT 1 (-8700 4600);
DOT 1 (-8775 5750);
DOT 1 (-8500 6300);
DOT 1 (-8075 6300);
DOT 1 (-8025 2300);
DOT 1 (-7600 3000);
DOT 1 (-7200 3000);
DOT 1 (-8000 3500);
DOT 1 (-7600 3500);
DOT 1 (-7200 3500);
DOT 1 (-6725 3000);
DOT 1 (-6725 3500);
DOT 1 (-4050 1875);
DOT 1 (-4875 2300);
DOT 1 (-4475 2300);
DOT 1 (-4050 2300);
DOT 1 (-7925 5100);
DOT 1 (-7675 5800);
DOT 1 (-7275 5800);
DOT 1 (-7675 6300);
DOT 1 (-7275 6300);
DOT 1 (-6850 6300);
DOT 1 (-4525 5100);
DOT 1 (-4150 5100);
DOT 1 (-3725 4675);
DOT 1 (-3725 5100);
DOT 1 (-6850 5800);
DOT 1 (-8000 3000);
FORCENOTE
PVDDIO_P1_PHASE3
(-9650 6225) 0;
DISPLAY LEFT (-9650 6225);
DISPLAY 1.021277 (-9650 6225);
PAINT WHITE (-9650 6225);
FORCENOTE
6.5*6.5*10.0
(-7400 1900) 0;
DISPLAY LEFT (-7400 1900);
DISPLAY 0.638298 (-7400 1900);
PAINT WHITE (-7400 1900);
FORCENOTE
DCR=0.17M OHM
(-7400 1850) 0;
DISPLAY LEFT (-7400 1850);
DISPLAY 0.638298 (-7400 1850);
PAINT WHITE (-7400 1850);
FORCENOTE
2ND=CV+22Y0EZ01
(-7400 1800) 0;
DISPLAY LEFT (-7400 1800);
DISPLAY 0.638298 (-7400 1800);
PAINT WHITE (-7400 1800);
FORCENOTE
ISAT:30A@100C
(-7400 1950) 0;
DISPLAY LEFT (-7400 1950);
DISPLAY 0.638298 (-7400 1950);
PAINT WHITE (-7400 1950);
FORCENOTE
HCME656510Q-221QL
(-7400 2000) 0;
DISPLAY LEFT (-7400 2000);
DISPLAY 0.638298 (-7400 2000);
PAINT WHITE (-7400 2000);
FORCENOTE
ISAT:70A@100C
(-5875 2575) 0;
DISPLAY LEFT (-5875 2575);
DISPLAY 0.638298 (-5875 2575);
PAINT WHITE (-5875 2575);
FORCENOTE
11.0*7.5*12.5
(-5875 2525) 0;
DISPLAY LEFT (-5875 2525);
DISPLAY 0.638298 (-5875 2525);
PAINT WHITE (-5875 2525);
FORCENOTE
2ND=CV+15^0TZ01
(-5875 2375) 0;
DISPLAY LEFT (-5875 2375);
DISPLAY 0.638298 (-5875 2375);
PAINT WHITE (-5875 2375);
FORCENOTE
DCR=2-3,0.27M OHM
(-5875 2425) 0;
DISPLAY LEFT (-5875 2425);
DISPLAY 0.638298 (-5875 2425);
PAINT WHITE (-5875 2425);
FORCENOTE
DCR=1-4,0.105M OHM
(-5875 2475) 0;
DISPLAY LEFT (-5875 2475);
DISPLAY 0.638298 (-5875 2475);
PAINT WHITE (-5875 2475);
FORCENOTE
PGL6303.151HLT
(-5875 2625) 0;
DISPLAY LEFT (-5875 2625);
DISPLAY 0.638298 (-5875 2625);
PAINT WHITE (-5875 2625);
FORCENOTE
2ND=CV+15^0TZ01
(-5625 5175) 0;
DISPLAY LEFT (-5625 5175);
DISPLAY 0.638298 (-5625 5175);
PAINT WHITE (-5625 5175);
FORCENOTE
DCR=1-4,0.105M OHM
(-5625 5275) 0;
DISPLAY LEFT (-5625 5275);
DISPLAY 0.638298 (-5625 5275);
PAINT WHITE (-5625 5275);
FORCENOTE
ISAT:70A@100C
(-5625 5375) 0;
DISPLAY LEFT (-5625 5375);
DISPLAY 0.638298 (-5625 5375);
PAINT WHITE (-5625 5375);
FORCENOTE
11.0*7.5*12.5
(-5625 5325) 0;
DISPLAY LEFT (-5625 5325);
DISPLAY 0.638298 (-5625 5325);
PAINT WHITE (-5625 5325);
FORCENOTE
PGL6303.151HLT
(-5625 5425) 0;
DISPLAY LEFT (-5625 5425);
DISPLAY 0.638298 (-5625 5425);
PAINT WHITE (-5625 5425);
FORCENOTE
DCR=2-3,0.27M OHM
(-5625 5225) 0;
DISPLAY LEFT (-5625 5225);
DISPLAY 0.638298 (-5625 5225);
PAINT WHITE (-5625 5225);
FORCENOTE
PVDDIO_P1_PHASE4
(-9650 3375) 0;
DISPLAY LEFT (-9650 3375);
DISPLAY 1.021277 (-9650 3375);
PAINT WHITE (-9650 3375);
QUIT
